(kicad_sch
	(version 20250114)
	(generator "eeschema")
	(generator_version "9.0")
	(paper "A3")
	(title_block
		(title "Kintex 410T devboard")
		(date "2024-04-03")
		(rev "1.1.2")
	)
	(junction
		(at 254 69.85)
		(diameter 0)
		(color 0 0 0 0)
	)
	(junction
		(at 147.32 69.85)
		(diameter 0)
		(color 0 0 0 0)
	)
	(junction
		(at 292.1 59.69)
		(diameter 0)
		(color 0 0 0 0)
	)
	(junction
		(at 147.32 59.69)
		(diameter 0)
		(color 0 0 0 0)
	)
	(junction
		(at 124.46 59.69)
		(diameter 0)
		(color 0 0 0 0)
	)
	(junction
		(at 132.08 59.69)
		(diameter 0)
		(color 0 0 0 0)
	)
	(junction
		(at 276.86 69.85)
		(diameter 0)
		(color 0 0 0 0)
	)
	(junction
		(at 284.48 59.69)
		(diameter 0)
		(color 0 0 0 0)
	)
	(junction
		(at 246.38 69.85)
		(diameter 0)
		(color 0 0 0 0)
	)
	(junction
		(at 261.62 69.85)
		(diameter 0)
		(color 0 0 0 0)
	)
	(junction
		(at 162.56 59.69)
		(diameter 0)
		(color 0 0 0 0)
	)
	(junction
		(at 246.38 59.69)
		(diameter 0)
		(color 0 0 0 0)
	)
	(junction
		(at 132.08 69.85)
		(diameter 0)
		(color 0 0 0 0)
	)
	(junction
		(at 254 59.69)
		(diameter 0)
		(color 0 0 0 0)
	)
	(junction
		(at 116.84 69.85)
		(diameter 0)
		(color 0 0 0 0)
	)
	(junction
		(at 284.48 69.85)
		(diameter 0)
		(color 0 0 0 0)
	)
	(junction
		(at 170.18 59.69)
		(diameter 0)
		(color 0 0 0 0)
	)
	(junction
		(at 269.24 59.69)
		(diameter 0)
		(color 0 0 0 0)
	)
	(junction
		(at 139.7 69.85)
		(diameter 0)
		(color 0 0 0 0)
	)
	(junction
		(at 261.62 59.69)
		(diameter 0)
		(color 0 0 0 0)
	)
	(junction
		(at 269.24 69.85)
		(diameter 0)
		(color 0 0 0 0)
	)
	(junction
		(at 292.1 69.85)
		(diameter 0)
		(color 0 0 0 0)
	)
	(junction
		(at 116.84 59.69)
		(diameter 0)
		(color 0 0 0 0)
	)
	(junction
		(at 162.56 69.85)
		(diameter 0)
		(color 0 0 0 0)
	)
	(junction
		(at 276.86 59.69)
		(diameter 0)
		(color 0 0 0 0)
	)
	(junction
		(at 238.76 59.69)
		(diameter 0)
		(color 0 0 0 0)
	)
	(junction
		(at 154.94 69.85)
		(diameter 0)
		(color 0 0 0 0)
	)
	(junction
		(at 154.94 59.69)
		(diameter 0)
		(color 0 0 0 0)
	)
	(junction
		(at 139.7 59.69)
		(diameter 0)
		(color 0 0 0 0)
	)
	(junction
		(at 124.46 69.85)
		(diameter 0)
		(color 0 0 0 0)
	)
	(no_connect
		(at 233.68 132.08)
	)
	(no_connect
		(at 233.68 104.14)
	)
	(no_connect
		(at 233.68 119.38)
	)
	(no_connect
		(at 179.07 114.3)
	)
	(no_connect
		(at 179.07 116.84)
	)
	(no_connect
		(at 179.07 119.38)
	)
	(no_connect
		(at 179.07 88.9)
	)
	(no_connect
		(at 179.07 91.44)
	)
	(no_connect
		(at 179.07 96.52)
	)
	(no_connect
		(at 179.07 99.06)
	)
	(no_connect
		(at 179.07 142.24)
	)
	(no_connect
		(at 179.07 101.6)
	)
	(no_connect
		(at 179.07 104.14)
	)
	(no_connect
		(at 179.07 106.68)
	)
	(no_connect
		(at 179.07 109.22)
	)
	(no_connect
		(at 179.07 111.76)
	)
	(no_connect
		(at 179.07 167.64)
	)
	(no_connect
		(at 179.07 172.72)
	)
	(no_connect
		(at 179.07 213.36)
	)
	(no_connect
		(at 233.68 91.44)
	)
	(no_connect
		(at 233.68 124.46)
	)
	(no_connect
		(at 233.68 116.84)
	)
	(no_connect
		(at 233.68 134.62)
	)
	(no_connect
		(at 233.68 195.58)
	)
	(no_connect
		(at 233.68 137.16)
	)
	(no_connect
		(at 233.68 101.6)
	)
	(no_connect
		(at 233.68 111.76)
	)
	(no_connect
		(at 233.68 157.48)
	)
	(no_connect
		(at 233.68 114.3)
	)
	(no_connect
		(at 233.68 93.98)
	)
	(no_connect
		(at 233.68 193.04)
	)
	(bus_entry
		(at 161.29 125.73)
		(size 1.27 1.27)
		(stroke
			(width 0)
			(type default)
		)
	)
	(bus_entry
		(at 161.29 179.07)
		(size 1.27 1.27)
		(stroke
			(width 0)
			(type default)
		)
	)
	(bus_entry
		(at 161.29 207.01)
		(size 1.27 1.27)
		(stroke
			(width 0)
			(type default)
		)
	)
	(bus_entry
		(at 161.29 151.13)
		(size 1.27 1.27)
		(stroke
			(width 0)
			(type default)
		)
	)
	(bus_entry
		(at 255.27 153.67)
		(size -1.27 1.27)
		(stroke
			(width 0)
			(type default)
		)
	)
	(bus_entry
		(at 321.31 186.69)
		(size -1.27 1.27)
		(stroke
			(width 0)
			(type default)
		)
	)
	(bus_entry
		(at 128.27 163.83)
		(size 1.27 1.27)
		(stroke
			(width 0)
			(type default)
		)
	)
	(bus_entry
		(at 288.29 127)
		(size 1.27 1.27)
		(stroke
			(width 0)
			(type default)
		)
	)
	(bus_entry
		(at 161.29 138.43)
		(size 1.27 1.27)
		(stroke
			(width 0)
			(type default)
		)
	)
	(bus_entry
		(at 321.31 171.45)
		(size -1.27 1.27)
		(stroke
			(width 0)
			(type default)
		)
	)
	(bus_entry
		(at 161.29 196.85)
		(size 1.27 1.27)
		(stroke
			(width 0)
			(type default)
		)
	)
	(bus_entry
		(at 128.27 204.47)
		(size 1.27 1.27)
		(stroke
			(width 0)
			(type default)
		)
	)
	(bus_entry
		(at 255.27 176.53)
		(size -1.27 1.27)
		(stroke
			(width 0)
			(type default)
		)
	)
	(bus_entry
		(at 161.29 130.81)
		(size 1.27 1.27)
		(stroke
			(width 0)
			(type default)
		)
	)
	(bus_entry
		(at 255.27 95.25)
		(size -1.27 1.27)
		(stroke
			(width 0)
			(type default)
		)
	)
	(bus_entry
		(at 255.27 158.75)
		(size -1.27 1.27)
		(stroke
			(width 0)
			(type default)
		)
	)
	(bus_entry
		(at 161.29 123.19)
		(size 1.27 1.27)
		(stroke
			(width 0)
			(type default)
		)
	)
	(bus_entry
		(at 128.27 168.91)
		(size 1.27 1.27)
		(stroke
			(width 0)
			(type default)
		)
	)
	(bus_entry
		(at 161.29 120.65)
		(size 1.27 1.27)
		(stroke
			(width 0)
			(type default)
		)
	)
	(bus_entry
		(at 161.29 194.31)
		(size 1.27 1.27)
		(stroke
			(width 0)
			(type default)
		)
	)
	(bus_entry
		(at 255.27 168.91)
		(size -1.27 1.27)
		(stroke
			(width 0)
			(type default)
		)
	)
	(bus_entry
		(at 255.27 151.13)
		(size -1.27 1.27)
		(stroke
			(width 0)
			(type default)
		)
	)
	(bus_entry
		(at 161.29 199.39)
		(size 1.27 1.27)
		(stroke
			(width 0)
			(type default)
		)
	)
	(bus_entry
		(at 255.27 166.37)
		(size -1.27 1.27)
		(stroke
			(width 0)
			(type default)
		)
	)
	(bus_entry
		(at 161.29 146.05)
		(size 1.27 1.27)
		(stroke
			(width 0)
			(type default)
		)
	)
	(bus_entry
		(at 255.27 158.75)
		(size -1.27 1.27)
		(stroke
			(width 0)
			(type default)
		)
	)
	(bus_entry
		(at 128.27 201.93)
		(size 1.27 1.27)
		(stroke
			(width 0)
			(type default)
		)
	)
	(bus_entry
		(at 161.29 191.77)
		(size 1.27 1.27)
		(stroke
			(width 0)
			(type default)
		)
	)
	(bus_entry
		(at 288.29 182.88)
		(size 1.27 1.27)
		(stroke
			(width 0)
			(type default)
		)
	)
	(bus_entry
		(at 255.27 179.07)
		(size -1.27 1.27)
		(stroke
			(width 0)
			(type default)
		)
	)
	(bus_entry
		(at 288.29 203.2)
		(size 1.27 1.27)
		(stroke
			(width 0)
			(type default)
		)
	)
	(bus_entry
		(at 278.13 105.41)
		(size -1.27 1.27)
		(stroke
			(width 0)
			(type default)
		)
	)
	(bus_entry
		(at 161.29 173.99)
		(size 1.27 1.27)
		(stroke
			(width 0)
			(type default)
		)
	)
	(bus_entry
		(at 255.27 143.51)
		(size -1.27 1.27)
		(stroke
			(width 0)
			(type default)
		)
	)
	(bus_entry
		(at 255.27 166.37)
		(size -1.27 1.27)
		(stroke
			(width 0)
			(type default)
		)
	)
	(bus_entry
		(at 255.27 140.97)
		(size -1.27 1.27)
		(stroke
			(width 0)
			(type default)
		)
	)
	(bus_entry
		(at 161.29 189.23)
		(size 1.27 1.27)
		(stroke
			(width 0)
			(type default)
		)
	)
	(bus_entry
		(at 255.27 146.05)
		(size -1.27 1.27)
		(stroke
			(width 0)
			(type default)
		)
	)
	(bus_entry
		(at 161.29 153.67)
		(size 1.27 1.27)
		(stroke
			(width 0)
			(type default)
		)
	)
	(bus_entry
		(at 161.29 186.69)
		(size 1.27 1.27)
		(stroke
			(width 0)
			(type default)
		)
	)
	(bus_entry
		(at 288.29 129.54)
		(size 1.27 1.27)
		(stroke
			(width 0)
			(type default)
		)
	)
	(bus_entry
		(at 288.29 210.82)
		(size 1.27 1.27)
		(stroke
			(width 0)
			(type default)
		)
	)
	(bus_entry
		(at 128.27 161.29)
		(size 1.27 1.27)
		(stroke
			(width 0)
			(type default)
		)
	)
	(bus_entry
		(at 320.04 198.12)
		(size 1.27 -1.27)
		(stroke
			(width 0)
			(type default)
		)
	)
	(bus_entry
		(at 128.27 156.21)
		(size 1.27 1.27)
		(stroke
			(width 0)
			(type default)
		)
	)
	(bus_entry
		(at 161.29 148.59)
		(size 1.27 1.27)
		(stroke
			(width 0)
			(type default)
		)
	)
	(bus_entry
		(at 255.27 176.53)
		(size -1.27 1.27)
		(stroke
			(width 0)
			(type default)
		)
	)
	(bus_entry
		(at 255.27 148.59)
		(size -1.27 1.27)
		(stroke
			(width 0)
			(type default)
		)
	)
	(bus_entry
		(at 255.27 120.65)
		(size -1.27 1.27)
		(stroke
			(width 0)
			(type default)
		)
	)
	(bus_entry
		(at 321.31 173.99)
		(size -1.27 1.27)
		(stroke
			(width 0)
			(type default)
		)
	)
	(bus_entry
		(at 255.27 95.25)
		(size -1.27 1.27)
		(stroke
			(width 0)
			(type default)
		)
	)
	(bus_entry
		(at 255.27 179.07)
		(size -1.27 1.27)
		(stroke
			(width 0)
			(type default)
		)
	)
	(bus_entry
		(at 161.29 133.35)
		(size 1.27 1.27)
		(stroke
			(width 0)
			(type default)
		)
	)
	(bus_entry
		(at 320.04 165.1)
		(size 1.27 -1.27)
		(stroke
			(width 0)
			(type default)
		)
	)
	(bus_entry
		(at 255.27 120.65)
		(size -1.27 1.27)
		(stroke
			(width 0)
			(type default)
		)
	)
	(bus_entry
		(at 255.27 146.05)
		(size -1.27 1.27)
		(stroke
			(width 0)
			(type default)
		)
	)
	(bus_entry
		(at 161.29 143.51)
		(size 1.27 1.27)
		(stroke
			(width 0)
			(type default)
		)
	)
	(bus_entry
		(at 255.27 161.29)
		(size -1.27 1.27)
		(stroke
			(width 0)
			(type default)
		)
	)
	(bus_entry
		(at 255.27 148.59)
		(size -1.27 1.27)
		(stroke
			(width 0)
			(type default)
		)
	)
	(bus_entry
		(at 161.29 128.27)
		(size 1.27 1.27)
		(stroke
			(width 0)
			(type default)
		)
	)
	(bus_entry
		(at 320.04 165.1)
		(size 1.27 -1.27)
		(stroke
			(width 0)
			(type default)
		)
	)
	(bus_entry
		(at 255.27 212.09)
		(size -1.27 1.27)
		(stroke
			(width 0)
			(type default)
		)
	)
	(bus_entry
		(at 255.27 138.43)
		(size -1.27 1.27)
		(stroke
			(width 0)
			(type default)
		)
	)
	(bus_entry
		(at 161.29 176.53)
		(size 1.27 1.27)
		(stroke
			(width 0)
			(type default)
		)
	)
	(bus_entry
		(at 161.29 209.55)
		(size 1.27 1.27)
		(stroke
			(width 0)
			(type default)
		)
	)
	(bus_entry
		(at 288.29 205.74)
		(size 1.27 1.27)
		(stroke
			(width 0)
			(type default)
		)
	)
	(bus_entry
		(at 320.04 200.66)
		(size 1.27 -1.27)
		(stroke
			(width 0)
			(type default)
		)
	)
	(bus_entry
		(at 255.27 97.79)
		(size -1.27 1.27)
		(stroke
			(width 0)
			(type default)
		)
	)
	(bus_entry
		(at 161.29 158.75)
		(size 1.27 1.27)
		(stroke
			(width 0)
			(type default)
		)
	)
	(bus_entry
		(at 161.29 135.89)
		(size 1.27 1.27)
		(stroke
			(width 0)
			(type default)
		)
	)
	(bus_entry
		(at 161.29 181.61)
		(size 1.27 1.27)
		(stroke
			(width 0)
			(type default)
		)
	)
	(bus_entry
		(at 288.29 208.28)
		(size 1.27 1.27)
		(stroke
			(width 0)
			(type default)
		)
	)
	(bus_entry
		(at 288.29 185.42)
		(size 1.27 1.27)
		(stroke
			(width 0)
			(type default)
		)
	)
	(bus_entry
		(at 161.29 92.71)
		(size 1.27 1.27)
		(stroke
			(width 0)
			(type default)
		)
	)
	(bus_entry
		(at 255.27 97.79)
		(size -1.27 1.27)
		(stroke
			(width 0)
			(type default)
		)
	)
	(bus_entry
		(at 278.13 107.95)
		(size -1.27 1.27)
		(stroke
			(width 0)
			(type default)
		)
	)
	(bus_entry
		(at 278.13 87.63)
		(size -1.27 1.27)
		(stroke
			(width 0)
			(type default)
		)
	)
	(bus_entry
		(at 161.29 184.15)
		(size 1.27 1.27)
		(stroke
			(width 0)
			(type default)
		)
	)
	(bus_entry
		(at 255.27 143.51)
		(size -1.27 1.27)
		(stroke
			(width 0)
			(type default)
		)
	)
	(bus_entry
		(at 321.31 189.23)
		(size -1.27 1.27)
		(stroke
			(width 0)
			(type default)
		)
	)
	(wire
		(pts
			(xy 233.68 165.1) (xy 320.04 165.1)
		)
		(stroke
			(width 0)
			(type default)
		)
	)
	(bus
		(pts
			(xy 259.08 81.28) (xy 256.54 81.28)
		)
		(stroke
			(width 0)
			(type default)
		)
	)
	(wire
		(pts
			(xy 238.76 59.69) (xy 236.22 59.69)
		)
		(stroke
			(width 0)
			(type default)
		)
	)
	(wire
		(pts
			(xy 124.46 69.85) (xy 124.46 67.31)
		)
		(stroke
			(width 0)
			(type default)
		)
	)
	(wire
		(pts
			(xy 162.56 93.98) (xy 179.07 93.98)
		)
		(stroke
			(width 0)
			(type default)
		)
	)
	(wire
		(pts
			(xy 269.24 69.85) (xy 269.24 67.31)
		)
		(stroke
			(width 0)
			(type default)
		)
	)
	(bus
		(pts
			(xy 255.27 95.25) (xy 255.27 97.79)
		)
		(stroke
			(width 0)
			(type default)
		)
	)
	(wire
		(pts
			(xy 254 67.31) (xy 254 69.85)
		)
		(stroke
			(width 0)
			(type default)
		)
	)
	(bus
		(pts
			(xy 161.29 92.71) (xy 161.29 120.65)
		)
		(stroke
			(width 0)
			(type default)
		)
	)
	(bus
		(pts
			(xy 321.31 189.23) (xy 321.31 196.85)
		)
		(stroke
			(width 0)
			(type default)
		)
	)
	(wire
		(pts
			(xy 284.48 59.69) (xy 292.1 59.69)
		)
		(stroke
			(width 0)
			(type default)
		)
	)
	(wire
		(pts
			(xy 292.1 69.85) (xy 292.1 67.31)
		)
		(stroke
			(width 0)
			(type default)
		)
	)
	(wire
		(pts
			(xy 233.68 109.22) (xy 276.86 109.22)
		)
		(stroke
			(width 0)
			(type default)
		)
	)
	(wire
		(pts
			(xy 162.56 69.85) (xy 154.94 69.85)
		)
		(stroke
			(width 0)
			(type default)
		)
	)
	(wire
		(pts
			(xy 162.56 180.34) (xy 179.07 180.34)
		)
		(stroke
			(width 0)
			(type default)
		)
	)
	(wire
		(pts
			(xy 176.53 85.09) (xy 179.07 85.09)
		)
		(stroke
			(width 0)
			(type default)
		)
	)
	(bus
		(pts
			(xy 321.31 163.83) (xy 321.31 161.29)
		)
		(stroke
			(width 0)
			(type default)
		)
	)
	(bus
		(pts
			(xy 289.56 128.27) (xy 289.56 130.81)
		)
		(stroke
			(width 0)
			(type default)
		)
	)
	(wire
		(pts
			(xy 254 167.64) (xy 233.68 167.64)
		)
		(stroke
			(width 0)
			(type default)
		)
	)
	(bus
		(pts
			(xy 278.13 82.55) (xy 279.4 81.28)
		)
		(stroke
			(width 0)
			(type default)
		)
	)
	(bus
		(pts
			(xy 161.29 153.67) (xy 161.29 158.75)
		)
		(stroke
			(width 0)
			(type default)
		)
	)
	(wire
		(pts
			(xy 254 147.32) (xy 233.68 147.32)
		)
		(stroke
			(width 0)
			(type default)
		)
	)
	(bus
		(pts
			(xy 161.29 158.75) (xy 161.29 173.99)
		)
		(stroke
			(width 0)
			(type default)
		)
	)
	(bus
		(pts
			(xy 128.27 156.21) (xy 128.27 161.29)
		)
		(stroke
			(width 0)
			(type default)
		)
	)
	(wire
		(pts
			(xy 162.56 193.04) (xy 179.07 193.04)
		)
		(stroke
			(width 0)
			(type default)
		)
	)
	(bus
		(pts
			(xy 255.27 143.51) (xy 255.27 146.05)
		)
		(stroke
			(width 0)
			(type default)
		)
	)
	(wire
		(pts
			(xy 292.1 59.69) (xy 292.1 62.23)
		)
		(stroke
			(width 0)
			(type default)
		)
	)
	(bus
		(pts
			(xy 161.29 186.69) (xy 161.29 189.23)
		)
		(stroke
			(width 0)
			(type default)
		)
	)
	(wire
		(pts
			(xy 233.68 187.96) (xy 320.04 187.96)
		)
		(stroke
			(width 0)
			(type default)
		)
	)
	(wire
		(pts
			(xy 162.56 132.08) (xy 179.07 132.08)
		)
		(stroke
			(width 0)
			(type default)
		)
	)
	(wire
		(pts
			(xy 261.62 69.85) (xy 261.62 67.31)
		)
		(stroke
			(width 0)
			(type default)
		)
	)
	(wire
		(pts
			(xy 176.53 59.69) (xy 176.53 85.09)
		)
		(stroke
			(width 0)
			(type default)
		)
	)
	(wire
		(pts
			(xy 288.29 182.88) (xy 233.68 182.88)
		)
		(stroke
			(width 0)
			(type default)
		)
	)
	(wire
		(pts
			(xy 284.48 62.23) (xy 284.48 59.69)
		)
		(stroke
			(width 0)
			(type default)
		)
	)
	(wire
		(pts
			(xy 254 59.69) (xy 254 62.23)
		)
		(stroke
			(width 0)
			(type default)
		)
	)
	(bus
		(pts
			(xy 161.29 123.19) (xy 161.29 125.73)
		)
		(stroke
			(width 0)
			(type default)
		)
	)
	(bus
		(pts
			(xy 321.31 186.69) (xy 321.31 173.99)
		)
		(stroke
			(width 0)
			(type default)
		)
	)
	(wire
		(pts
			(xy 162.56 182.88) (xy 179.07 182.88)
		)
		(stroke
			(width 0)
			(type default)
		)
	)
	(wire
		(pts
			(xy 254 177.8) (xy 233.68 177.8)
		)
		(stroke
			(width 0)
			(type default)
		)
	)
	(wire
		(pts
			(xy 254 180.34) (xy 233.68 180.34)
		)
		(stroke
			(width 0)
			(type default)
		)
	)
	(bus
		(pts
			(xy 278.13 105.41) (xy 278.13 107.95)
		)
		(stroke
			(width 0)
			(type default)
		)
	)
	(bus
		(pts
			(xy 128.27 168.91) (xy 128.27 201.93)
		)
		(stroke
			(width 0)
			(type default)
		)
	)
	(wire
		(pts
			(xy 170.18 62.23) (xy 170.18 59.69)
		)
		(stroke
			(width 0)
			(type default)
		)
	)
	(wire
		(pts
			(xy 233.68 172.72) (xy 320.04 172.72)
		)
		(stroke
			(width 0)
			(type default)
		)
	)
	(wire
		(pts
			(xy 288.29 210.82) (xy 233.68 210.82)
		)
		(stroke
			(width 0)
			(type default)
		)
	)
	(bus
		(pts
			(xy 255.27 166.37) (xy 255.27 168.91)
		)
		(stroke
			(width 0)
			(type default)
		)
	)
	(wire
		(pts
			(xy 238.76 69.85) (xy 246.38 69.85)
		)
		(stroke
			(width 0)
			(type default)
		)
	)
	(bus
		(pts
			(xy 128.27 156.21) (xy 128.27 152.4)
		)
		(stroke
			(width 0)
			(type default)
		)
	)
	(bus
		(pts
			(xy 161.29 120.65) (xy 161.29 123.19)
		)
		(stroke
			(width 0)
			(type default)
		)
	)
	(bus
		(pts
			(xy 278.13 82.55) (xy 278.13 87.63)
		)
		(stroke
			(width 0)
			(type default)
		)
	)
	(wire
		(pts
			(xy 233.68 88.9) (xy 276.86 88.9)
		)
		(stroke
			(width 0)
			(type default)
		)
	)
	(bus
		(pts
			(xy 280.67 81.28) (xy 279.4 81.28)
		)
		(stroke
			(width 0)
			(type default)
		)
	)
	(bus
		(pts
			(xy 161.29 196.85) (xy 161.29 199.39)
		)
		(stroke
			(width 0)
			(type default)
		)
	)
	(bus
		(pts
			(xy 130.81 87.63) (xy 160.02 87.63)
		)
		(stroke
			(width 0)
			(type default)
		)
	)
	(wire
		(pts
			(xy 147.32 69.85) (xy 147.32 67.31)
		)
		(stroke
			(width 0)
			(type default)
		)
	)
	(wire
		(pts
			(xy 147.32 69.85) (xy 139.7 69.85)
		)
		(stroke
			(width 0)
			(type default)
		)
	)
	(wire
		(pts
			(xy 162.56 127) (xy 179.07 127)
		)
		(stroke
			(width 0)
			(type default)
		)
	)
	(bus
		(pts
			(xy 161.29 176.53) (xy 161.29 179.07)
		)
		(stroke
			(width 0)
			(type default)
		)
	)
	(wire
		(pts
			(xy 162.56 139.7) (xy 179.07 139.7)
		)
		(stroke
			(width 0)
			(type default)
		)
	)
	(wire
		(pts
			(xy 129.54 205.74) (xy 179.07 205.74)
		)
		(stroke
			(width 0)
			(type default)
		)
	)
	(bus
		(pts
			(xy 255.27 97.79) (xy 255.27 120.65)
		)
		(stroke
			(width 0)
			(type default)
		)
	)
	(bus
		(pts
			(xy 321.31 196.85) (xy 321.31 199.39)
		)
		(stroke
			(width 0)
			(type default)
		)
	)
	(wire
		(pts
			(xy 139.7 59.69) (xy 147.32 59.69)
		)
		(stroke
			(width 0)
			(type default)
		)
	)
	(wire
		(pts
			(xy 254 152.4) (xy 233.68 152.4)
		)
		(stroke
			(width 0)
			(type default)
		)
	)
	(wire
		(pts
			(xy 246.38 69.85) (xy 254 69.85)
		)
		(stroke
			(width 0)
			(type default)
		)
	)
	(bus
		(pts
			(xy 321.31 186.69) (xy 321.31 189.23)
		)
		(stroke
			(width 0)
			(type default)
		)
	)
	(bus
		(pts
			(xy 255.27 168.91) (xy 255.27 176.53)
		)
		(stroke
			(width 0)
			(type default)
		)
	)
	(wire
		(pts
			(xy 162.56 210.82) (xy 179.07 210.82)
		)
		(stroke
			(width 0)
			(type default)
		)
	)
	(wire
		(pts
			(xy 269.24 59.69) (xy 261.62 59.69)
		)
		(stroke
			(width 0)
			(type default)
		)
	)
	(wire
		(pts
			(xy 288.29 208.28) (xy 233.68 208.28)
		)
		(stroke
			(width 0)
			(type default)
		)
	)
	(wire
		(pts
			(xy 129.54 170.18) (xy 179.07 170.18)
		)
		(stroke
			(width 0)
			(type default)
		)
	)
	(bus
		(pts
			(xy 289.56 186.69) (xy 289.56 204.47)
		)
		(stroke
			(width 0)
			(type default)
		)
	)
	(wire
		(pts
			(xy 147.32 62.23) (xy 147.32 59.69)
		)
		(stroke
			(width 0)
			(type default)
		)
	)
	(bus
		(pts
			(xy 161.29 88.9) (xy 161.29 92.71)
		)
		(stroke
			(width 0)
			(type default)
		)
	)
	(bus
		(pts
			(xy 255.27 151.13) (xy 255.27 153.67)
		)
		(stroke
			(width 0)
			(type default)
		)
	)
	(wire
		(pts
			(xy 179.07 124.46) (xy 162.56 124.46)
		)
		(stroke
			(width 0)
			(type default)
		)
	)
	(wire
		(pts
			(xy 288.29 203.2) (xy 233.68 203.2)
		)
		(stroke
			(width 0)
			(type default)
		)
	)
	(bus
		(pts
			(xy 289.56 207.01) (xy 289.56 209.55)
		)
		(stroke
			(width 0)
			(type default)
		)
	)
	(wire
		(pts
			(xy 113.03 57.15) (xy 113.03 59.69)
		)
		(stroke
			(width 0)
			(type default)
		)
	)
	(wire
		(pts
			(xy 116.84 59.69) (xy 116.84 62.23)
		)
		(stroke
			(width 0)
			(type default)
		)
	)
	(wire
		(pts
			(xy 254 99.06) (xy 233.68 99.06)
		)
		(stroke
			(width 0)
			(type default)
		)
	)
	(wire
		(pts
			(xy 162.56 69.85) (xy 170.18 69.85)
		)
		(stroke
			(width 0)
			(type default)
		)
	)
	(wire
		(pts
			(xy 162.56 208.28) (xy 179.07 208.28)
		)
		(stroke
			(width 0)
			(type default)
		)
	)
	(wire
		(pts
			(xy 162.56 177.8) (xy 179.07 177.8)
		)
		(stroke
			(width 0)
			(type default)
		)
	)
	(bus
		(pts
			(xy 161.29 143.51) (xy 161.29 146.05)
		)
		(stroke
			(width 0)
			(type default)
		)
	)
	(bus
		(pts
			(xy 255.27 179.07) (xy 255.27 212.09)
		)
		(stroke
			(width 0)
			(type default)
		)
	)
	(wire
		(pts
			(xy 254 170.18) (xy 233.68 170.18)
		)
		(stroke
			(width 0)
			(type default)
		)
	)
	(bus
		(pts
			(xy 161.29 125.73) (xy 161.29 128.27)
		)
		(stroke
			(width 0)
			(type default)
		)
	)
	(bus
		(pts
			(xy 161.29 151.13) (xy 161.29 153.67)
		)
		(stroke
			(width 0)
			(type default)
		)
	)
	(wire
		(pts
			(xy 254 121.92) (xy 233.68 121.92)
		)
		(stroke
			(width 0)
			(type default)
		)
	)
	(bus
		(pts
			(xy 255.27 148.59) (xy 255.27 151.13)
		)
		(stroke
			(width 0)
			(type default)
		)
	)
	(bus
		(pts
			(xy 289.56 209.55) (xy 289.56 212.09)
		)
		(stroke
			(width 0)
			(type default)
		)
	)
	(wire
		(pts
			(xy 284.48 59.69) (xy 276.86 59.69)
		)
		(stroke
			(width 0)
			(type default)
		)
	)
	(bus
		(pts
			(xy 321.31 161.29) (xy 322.58 160.02)
		)
		(stroke
			(width 0)
			(type default)
		)
	)
	(bus
		(pts
			(xy 278.13 87.63) (xy 278.13 105.41)
		)
		(stroke
			(width 0)
			(type default)
		)
	)
	(wire
		(pts
			(xy 284.48 69.85) (xy 276.86 69.85)
		)
		(stroke
			(width 0)
			(type default)
		)
	)
	(wire
		(pts
			(xy 254 160.02) (xy 233.68 160.02)
		)
		(stroke
			(width 0)
			(type default)
		)
	)
	(wire
		(pts
			(xy 162.56 59.69) (xy 170.18 59.69)
		)
		(stroke
			(width 0)
			(type default)
		)
	)
	(wire
		(pts
			(xy 116.84 59.69) (xy 124.46 59.69)
		)
		(stroke
			(width 0)
			(type default)
		)
	)
	(bus
		(pts
			(xy 255.27 82.55) (xy 255.27 95.25)
		)
		(stroke
			(width 0)
			(type default)
		)
	)
	(bus
		(pts
			(xy 289.56 204.47) (xy 289.56 207.01)
		)
		(stroke
			(width 0)
			(type default)
		)
	)
	(wire
		(pts
			(xy 288.29 205.74) (xy 233.68 205.74)
		)
		(stroke
			(width 0)
			(type default)
		)
	)
	(wire
		(pts
			(xy 162.56 137.16) (xy 179.07 137.16)
		)
		(stroke
			(width 0)
			(type default)
		)
	)
	(wire
		(pts
			(xy 124.46 59.69) (xy 132.08 59.69)
		)
		(stroke
			(width 0)
			(type default)
		)
	)
	(wire
		(pts
			(xy 124.46 69.85) (xy 132.08 69.85)
		)
		(stroke
			(width 0)
			(type default)
		)
	)
	(wire
		(pts
			(xy 261.62 69.85) (xy 254 69.85)
		)
		(stroke
			(width 0)
			(type default)
		)
	)
	(wire
		(pts
			(xy 269.24 69.85) (xy 261.62 69.85)
		)
		(stroke
			(width 0)
			(type default)
		)
	)
	(wire
		(pts
			(xy 238.76 62.23) (xy 238.76 59.69)
		)
		(stroke
			(width 0)
			(type default)
		)
	)
	(wire
		(pts
			(xy 233.68 175.26) (xy 320.04 175.26)
		)
		(stroke
			(width 0)
			(type default)
		)
	)
	(wire
		(pts
			(xy 162.56 59.69) (xy 162.56 62.23)
		)
		(stroke
			(width 0)
			(type default)
		)
	)
	(wire
		(pts
			(xy 139.7 59.69) (xy 139.7 62.23)
		)
		(stroke
			(width 0)
			(type default)
		)
	)
	(wire
		(pts
			(xy 233.68 139.7) (xy 254 139.7)
		)
		(stroke
			(width 0)
			(type default)
		)
	)
	(bus
		(pts
			(xy 289.56 212.09) (xy 289.56 214.63)
		)
		(stroke
			(width 0)
			(type default)
		)
	)
	(bus
		(pts
			(xy 255.27 138.43) (xy 255.27 140.97)
		)
		(stroke
			(width 0)
			(type default)
		)
	)
	(wire
		(pts
			(xy 154.94 59.69) (xy 162.56 59.69)
		)
		(stroke
			(width 0)
			(type default)
		)
	)
	(wire
		(pts
			(xy 292.1 59.69) (xy 298.45 59.69)
		)
		(stroke
			(width 0)
			(type default)
		)
	)
	(wire
		(pts
			(xy 288.29 185.42) (xy 233.68 185.42)
		)
		(stroke
			(width 0)
			(type default)
		)
	)
	(wire
		(pts
			(xy 276.86 67.31) (xy 276.86 69.85)
		)
		(stroke
			(width 0)
			(type default)
		)
	)
	(wire
		(pts
			(xy 132.08 67.31) (xy 132.08 69.85)
		)
		(stroke
			(width 0)
			(type default)
		)
	)
	(bus
		(pts
			(xy 128.27 161.29) (xy 128.27 163.83)
		)
		(stroke
			(width 0)
			(type default)
		)
	)
	(wire
		(pts
			(xy 154.94 67.31) (xy 154.94 69.85)
		)
		(stroke
			(width 0)
			(type default)
		)
	)
	(wire
		(pts
			(xy 233.68 144.78) (xy 254 144.78)
		)
		(stroke
			(width 0)
			(type default)
		)
	)
	(wire
		(pts
			(xy 116.84 67.31) (xy 116.84 69.85)
		)
		(stroke
			(width 0)
			(type default)
		)
	)
	(wire
		(pts
			(xy 284.48 69.85) (xy 292.1 69.85)
		)
		(stroke
			(width 0)
			(type default)
		)
	)
	(bus
		(pts
			(xy 255.27 82.55) (xy 256.54 81.28)
		)
		(stroke
			(width 0)
			(type default)
		)
	)
	(wire
		(pts
			(xy 254 149.86) (xy 233.68 149.86)
		)
		(stroke
			(width 0)
			(type default)
		)
	)
	(bus
		(pts
			(xy 161.29 189.23) (xy 161.29 191.77)
		)
		(stroke
			(width 0)
			(type default)
		)
	)
	(wire
		(pts
			(xy 288.29 127) (xy 233.68 127)
		)
		(stroke
			(width 0)
			(type default)
		)
	)
	(wire
		(pts
			(xy 162.56 200.66) (xy 179.07 200.66)
		)
		(stroke
			(width 0)
			(type default)
		)
	)
	(wire
		(pts
			(xy 179.07 144.78) (xy 162.56 144.78)
		)
		(stroke
			(width 0)
			(type default)
		)
	)
	(wire
		(pts
			(xy 276.86 59.69) (xy 269.24 59.69)
		)
		(stroke
			(width 0)
			(type default)
		)
	)
	(wire
		(pts
			(xy 170.18 59.69) (xy 176.53 59.69)
		)
		(stroke
			(width 0)
			(type default)
		)
	)
	(bus
		(pts
			(xy 161.29 191.77) (xy 161.29 194.31)
		)
		(stroke
			(width 0)
			(type default)
		)
	)
	(bus
		(pts
			(xy 160.02 87.63) (xy 161.29 88.9)
		)
		(stroke
			(width 0)
			(type default)
		)
	)
	(wire
		(pts
			(xy 162.56 147.32) (xy 179.07 147.32)
		)
		(stroke
			(width 0)
			(type default)
		)
	)
	(bus
		(pts
			(xy 128.27 152.4) (xy 127 151.13)
		)
		(stroke
			(width 0)
			(type default)
		)
	)
	(bus
		(pts
			(xy 325.12 160.02) (xy 322.58 160.02)
		)
		(stroke
			(width 0)
			(type default)
		)
	)
	(wire
		(pts
			(xy 162.56 129.54) (xy 179.07 129.54)
		)
		(stroke
			(width 0)
			(type default)
		)
	)
	(wire
		(pts
			(xy 116.84 69.85) (xy 124.46 69.85)
		)
		(stroke
			(width 0)
			(type default)
		)
	)
	(bus
		(pts
			(xy 255.27 158.75) (xy 255.27 161.29)
		)
		(stroke
			(width 0)
			(type default)
		)
	)
	(wire
		(pts
			(xy 233.68 190.5) (xy 320.04 190.5)
		)
		(stroke
			(width 0)
			(type default)
		)
	)
	(wire
		(pts
			(xy 132.08 59.69) (xy 132.08 62.23)
		)
		(stroke
			(width 0)
			(type default)
		)
	)
	(wire
		(pts
			(xy 162.56 198.12) (xy 179.07 198.12)
		)
		(stroke
			(width 0)
			(type default)
		)
	)
	(bus
		(pts
			(xy 161.29 148.59) (xy 161.29 151.13)
		)
		(stroke
			(width 0)
			(type default)
		)
	)
	(bus
		(pts
			(xy 161.29 173.99) (xy 161.29 176.53)
		)
		(stroke
			(width 0)
			(type default)
		)
	)
	(bus
		(pts
			(xy 161.29 146.05) (xy 161.29 148.59)
		)
		(stroke
			(width 0)
			(type default)
		)
	)
	(wire
		(pts
			(xy 124.46 62.23) (xy 124.46 59.69)
		)
		(stroke
			(width 0)
			(type default)
		)
	)
	(wire
		(pts
			(xy 236.22 59.69) (xy 236.22 85.09)
		)
		(stroke
			(width 0)
			(type default)
		)
	)
	(wire
		(pts
			(xy 269.24 59.69) (xy 269.24 62.23)
		)
		(stroke
			(width 0)
			(type default)
		)
	)
	(wire
		(pts
			(xy 162.56 154.94) (xy 179.07 154.94)
		)
		(stroke
			(width 0)
			(type default)
		)
	)
	(wire
		(pts
			(xy 261.62 59.69) (xy 254 59.69)
		)
		(stroke
			(width 0)
			(type default)
		)
	)
	(wire
		(pts
			(xy 292.1 69.85) (xy 292.1 71.12)
		)
		(stroke
			(width 0)
			(type default)
		)
	)
	(wire
		(pts
			(xy 162.56 175.26) (xy 179.07 175.26)
		)
		(stroke
			(width 0)
			(type default)
		)
	)
	(bus
		(pts
			(xy 161.29 199.39) (xy 161.29 207.01)
		)
		(stroke
			(width 0)
			(type default)
		)
	)
	(bus
		(pts
			(xy 289.56 214.63) (xy 290.83 215.9)
		)
		(stroke
			(width 0)
			(type default)
		)
	)
	(wire
		(pts
			(xy 147.32 59.69) (xy 154.94 59.69)
		)
		(stroke
			(width 0)
			(type default)
		)
	)
	(bus
		(pts
			(xy 293.37 215.9) (xy 290.83 215.9)
		)
		(stroke
			(width 0)
			(type default)
		)
	)
	(bus
		(pts
			(xy 128.27 163.83) (xy 128.27 168.91)
		)
		(stroke
			(width 0)
			(type default)
		)
	)
	(wire
		(pts
			(xy 162.56 152.4) (xy 179.07 152.4)
		)
		(stroke
			(width 0)
			(type default)
		)
	)
	(wire
		(pts
			(xy 162.56 149.86) (xy 179.07 149.86)
		)
		(stroke
			(width 0)
			(type default)
		)
	)
	(wire
		(pts
			(xy 116.84 69.85) (xy 116.84 71.12)
		)
		(stroke
			(width 0)
			(type default)
		)
	)
	(wire
		(pts
			(xy 154.94 59.69) (xy 154.94 62.23)
		)
		(stroke
			(width 0)
			(type default)
		)
	)
	(bus
		(pts
			(xy 161.29 133.35) (xy 161.29 135.89)
		)
		(stroke
			(width 0)
			(type default)
		)
	)
	(wire
		(pts
			(xy 162.56 190.5) (xy 179.07 190.5)
		)
		(stroke
			(width 0)
			(type default)
		)
	)
	(wire
		(pts
			(xy 162.56 187.96) (xy 179.07 187.96)
		)
		(stroke
			(width 0)
			(type default)
		)
	)
	(wire
		(pts
			(xy 254 162.56) (xy 233.68 162.56)
		)
		(stroke
			(width 0)
			(type default)
		)
	)
	(wire
		(pts
			(xy 233.68 200.66) (xy 320.04 200.66)
		)
		(stroke
			(width 0)
			(type default)
		)
	)
	(wire
		(pts
			(xy 162.56 121.92) (xy 179.07 121.92)
		)
		(stroke
			(width 0)
			(type default)
		)
	)
	(wire
		(pts
			(xy 284.48 69.85) (xy 284.48 67.31)
		)
		(stroke
			(width 0)
			(type default)
		)
	)
	(wire
		(pts
			(xy 113.03 59.69) (xy 116.84 59.69)
		)
		(stroke
			(width 0)
			(type default)
		)
	)
	(wire
		(pts
			(xy 162.56 185.42) (xy 179.07 185.42)
		)
		(stroke
			(width 0)
			(type default)
		)
	)
	(wire
		(pts
			(xy 254 59.69) (xy 246.38 59.69)
		)
		(stroke
			(width 0)
			(type default)
		)
	)
	(wire
		(pts
			(xy 132.08 59.69) (xy 139.7 59.69)
		)
		(stroke
			(width 0)
			(type default)
		)
	)
	(bus
		(pts
			(xy 161.29 194.31) (xy 161.29 196.85)
		)
		(stroke
			(width 0)
			(type default)
		)
	)
	(bus
		(pts
			(xy 321.31 171.45) (xy 321.31 163.83)
		)
		(stroke
			(width 0)
			(type default)
		)
	)
	(wire
		(pts
			(xy 139.7 69.85) (xy 132.08 69.85)
		)
		(stroke
			(width 0)
			(type default)
		)
	)
	(wire
		(pts
			(xy 246.38 59.69) (xy 246.38 62.23)
		)
		(stroke
			(width 0)
			(type default)
		)
	)
	(wire
		(pts
			(xy 233.68 198.12) (xy 320.04 198.12)
		)
		(stroke
			(width 0)
			(type default)
		)
	)
	(wire
		(pts
			(xy 233.68 106.68) (xy 276.86 106.68)
		)
		(stroke
			(width 0)
			(type default)
		)
	)
	(wire
		(pts
			(xy 261.62 62.23) (xy 261.62 59.69)
		)
		(stroke
			(width 0)
			(type default)
		)
	)
	(bus
		(pts
			(xy 161.29 179.07) (xy 161.29 181.61)
		)
		(stroke
			(width 0)
			(type default)
		)
	)
	(wire
		(pts
			(xy 129.54 165.1) (xy 179.07 165.1)
		)
		(stroke
			(width 0)
			(type default)
		)
	)
	(bus
		(pts
			(xy 161.29 138.43) (xy 161.29 143.51)
		)
		(stroke
			(width 0)
			(type default)
		)
	)
	(bus
		(pts
			(xy 255.27 153.67) (xy 255.27 158.75)
		)
		(stroke
			(width 0)
			(type default)
		)
	)
	(bus
		(pts
			(xy 289.56 184.15) (xy 289.56 186.69)
		)
		(stroke
			(width 0)
			(type default)
		)
	)
	(wire
		(pts
			(xy 238.76 67.31) (xy 238.76 69.85)
		)
		(stroke
			(width 0)
			(type default)
		)
	)
	(bus
		(pts
			(xy 161.29 181.61) (xy 161.29 184.15)
		)
		(stroke
			(width 0)
			(type default)
		)
	)
	(bus
		(pts
			(xy 289.56 130.81) (xy 289.56 184.15)
		)
		(stroke
			(width 0)
			(type default)
		)
	)
	(bus
		(pts
			(xy 255.27 161.29) (xy 255.27 166.37)
		)
		(stroke
			(width 0)
			(type default)
		)
	)
	(bus
		(pts
			(xy 128.27 204.47) (xy 128.27 201.93)
		)
		(stroke
			(width 0)
			(type default)
		)
	)
	(bus
		(pts
			(xy 161.29 135.89) (xy 161.29 138.43)
		)
		(stroke
			(width 0)
			(type default)
		)
	)
	(wire
		(pts
			(xy 162.56 69.85) (xy 162.56 67.31)
		)
		(stroke
			(width 0)
			(type default)
		)
	)
	(bus
		(pts
			(xy 255.27 146.05) (xy 255.27 148.59)
		)
		(stroke
			(width 0)
			(type default)
		)
	)
	(wire
		(pts
			(xy 254 142.24) (xy 233.68 142.24)
		)
		(stroke
			(width 0)
			(type default)
		)
	)
	(wire
		(pts
			(xy 154.94 69.85) (xy 147.32 69.85)
		)
		(stroke
			(width 0)
			(type default)
		)
	)
	(bus
		(pts
			(xy 161.29 184.15) (xy 161.29 186.69)
		)
		(stroke
			(width 0)
			(type default)
		)
	)
	(wire
		(pts
			(xy 129.54 162.56) (xy 179.07 162.56)
		)
		(stroke
			(width 0)
			(type default)
		)
	)
	(wire
		(pts
			(xy 233.68 154.94) (xy 254 154.94)
		)
		(stroke
			(width 0)
			(type default)
		)
	)
	(bus
		(pts
			(xy 255.27 176.53) (xy 255.27 179.07)
		)
		(stroke
			(width 0)
			(type default)
		)
	)
	(wire
		(pts
			(xy 276.86 69.85) (xy 269.24 69.85)
		)
		(stroke
			(width 0)
			(type default)
		)
	)
	(wire
		(pts
			(xy 233.68 129.54) (xy 288.29 129.54)
		)
		(stroke
			(width 0)
			(type default)
		)
	)
	(wire
		(pts
			(xy 236.22 85.09) (xy 233.68 85.09)
		)
		(stroke
			(width 0)
			(type default)
		)
	)
	(wire
		(pts
			(xy 139.7 69.85) (xy 139.7 67.31)
		)
		(stroke
			(width 0)
			(type default)
		)
	)
	(wire
		(pts
			(xy 254 213.36) (xy 233.68 213.36)
		)
		(stroke
			(width 0)
			(type default)
		)
	)
	(bus
		(pts
			(xy 161.29 130.81) (xy 161.29 133.35)
		)
		(stroke
			(width 0)
			(type default)
		)
	)
	(bus
		(pts
			(xy 161.29 207.01) (xy 161.29 209.55)
		)
		(stroke
			(width 0)
			(type default)
		)
	)
	(wire
		(pts
			(xy 246.38 69.85) (xy 246.38 67.31)
		)
		(stroke
			(width 0)
			(type default)
		)
	)
	(wire
		(pts
			(xy 162.56 134.62) (xy 179.07 134.62)
		)
		(stroke
			(width 0)
			(type default)
		)
	)
	(bus
		(pts
			(xy 120.65 151.13) (xy 127 151.13)
		)
		(stroke
			(width 0)
			(type default)
		)
	)
	(wire
		(pts
			(xy 129.54 203.2) (xy 179.07 203.2)
		)
		(stroke
			(width 0)
			(type default)
		)
	)
	(bus
		(pts
			(xy 321.31 173.99) (xy 321.31 171.45)
		)
		(stroke
			(width 0)
			(type default)
		)
	)
	(wire
		(pts
			(xy 246.38 59.69) (xy 238.76 59.69)
		)
		(stroke
			(width 0)
			(type default)
		)
	)
	(wire
		(pts
			(xy 162.56 160.02) (xy 179.07 160.02)
		)
		(stroke
			(width 0)
			(type default)
		)
	)
	(wire
		(pts
			(xy 170.18 69.85) (xy 170.18 67.31)
		)
		(stroke
			(width 0)
			(type default)
		)
	)
	(bus
		(pts
			(xy 161.29 128.27) (xy 161.29 130.81)
		)
		(stroke
			(width 0)
			(type default)
		)
	)
	(bus
		(pts
			(xy 255.27 140.97) (xy 255.27 143.51)
		)
		(stroke
			(width 0)
			(type default)
		)
	)
	(wire
		(pts
			(xy 254 96.52) (xy 233.68 96.52)
		)
		(stroke
			(width 0)
			(type default)
		)
	)
	(wire
		(pts
			(xy 298.45 57.15) (xy 298.45 59.69)
		)
		(stroke
			(width 0)
			(type default)
		)
	)
	(bus
		(pts
			(xy 255.27 120.65) (xy 255.27 138.43)
		)
		(stroke
			(width 0)
			(type default)
		)
	)
	(wire
		(pts
			(xy 276.86 59.69) (xy 276.86 62.23)
		)
		(stroke
			(width 0)
			(type default)
		)
	)
	(wire
		(pts
			(xy 162.56 195.58) (xy 179.07 195.58)
		)
		(stroke
			(width 0)
			(type default)
		)
	)
	(wire
		(pts
			(xy 129.54 157.48) (xy 179.07 157.48)
		)
		(stroke
			(width 0)
			(type default)
		)
	)
	(label "HDMI.CLK_N"
		(at 267.97 205.74 0)
		(effects
			(font
				(size 1.27 1.27)
			)
			(justify left bottom)
		)
	)
	(label "GBE_RGMII.REFCLK"
		(at 234.95 167.64 0)
		(effects
			(font
				(size 1.27 1.27)
			)
			(justify left bottom)
		)
	)
	(label "USER_IO.B12"
		(at 176.53 121.92 180)
		(effects
			(font
				(size 1.27 1.27)
			)
			(justify right bottom)
		)
	)
	(label "USB_HOST.~{CS}"
		(at 300.99 175.26 0)
		(effects
			(font
				(size 1.27 1.27)
			)
			(justify left bottom)
		)
	)
	(label "FMC.CLK_DIR"
		(at 257.81 106.68 0)
		(effects
			(font
				(size 1.27 1.27)
			)
			(justify left bottom)
		)
	)
	(label "USER_IO.B24"
		(at 176.53 137.16 180)
		(effects
			(font
				(size 1.27 1.27)
			)
			(justify right bottom)
		)
	)
	(label "USER_IO.B23"
		(at 176.53 187.96 180)
		(effects
			(font
				(size 1.27 1.27)
			)
			(justify right bottom)
		)
	)
	(label "GBE_RGMII.RX_DV"
		(at 234.95 213.36 0)
		(effects
			(font
				(size 1.27 1.27)
			)
			(justify left bottom)
		)
	)
	(label "HDMI.CLK_P"
		(at 267.97 203.2 0)
		(effects
			(font
				(size 1.27 1.27)
			)
			(justify left bottom)
		)
	)
	(label "USR_FLASH_1.CLK"
		(at 149.86 170.18 180)
		(effects
			(font
				(size 1.27 1.27)
			)
			(justify right bottom)
		)
	)
	(label "USB_HOST.~{RESET}"
		(at 300.99 165.1 0)
		(effects
			(font
				(size 1.27 1.27)
			)
			(justify left bottom)
		)
	)
	(label "USER_IO.B32"
		(at 176.53 160.02 180)
		(effects
			(font
				(size 1.27 1.27)
			)
			(justify right bottom)
		)
	)
	(label "GBE_RGMII.RXD1"
		(at 234.95 162.56 0)
		(effects
			(font
				(size 1.27 1.27)
			)
			(justify left bottom)
		)
	)
	(label "USB_HOST.CLK"
		(at 300.99 187.96 0)
		(effects
			(font
				(size 1.27 1.27)
			)
			(justify left bottom)
		)
	)
	(label "USER_IO.B11"
		(at 176.53 139.7 180)
		(effects
			(font
				(size 1.27 1.27)
			)
			(justify right bottom)
		)
	)
	(label "USER_IO.B10"
		(at 176.53 124.46 180)
		(effects
			(font
				(size 1.27 1.27)
			)
			(justify right bottom)
		)
	)
	(label "GBE_RGMII.TX_EN"
		(at 234.95 99.06 0)
		(effects
			(font
				(size 1.27 1.27)
			)
			(justify left bottom)
		)
	)
	(label "USER_IO.B8"
		(at 176.53 93.98 180)
		(effects
			(font
				(size 1.27 1.27)
			)
			(justify right bottom)
		)
	)
	(label "USER_IO.B16"
		(at 176.53 129.54 180)
		(effects
			(font
				(size 1.27 1.27)
			)
			(justify right bottom)
		)
	)
	(label "USER_IO.B30"
		(at 176.53 154.94 180)
		(effects
			(font
				(size 1.27 1.27)
			)
			(justify right bottom)
		)
	)
	(label "GBE_RGMII.RXD3"
		(at 234.95 149.86 0)
		(effects
			(font
				(size 1.27 1.27)
			)
			(justify left bottom)
		)
	)
	(label "USB_HOST.INT"
		(at 300.99 198.12 0)
		(effects
			(font
				(size 1.27 1.27)
			)
			(justify left bottom)
		)
	)
	(label "USER_IO.B17"
		(at 176.53 198.12 180)
		(effects
			(font
				(size 1.27 1.27)
			)
			(justify right bottom)
		)
	)
	(label "USR_FLASH_1.DQ2"
		(at 149.86 203.2 180)
		(effects
			(font
				(size 1.27 1.27)
			)
			(justify right bottom)
		)
	)
	(label "FMC.~{PERST}"
		(at 257.81 88.9 0)
		(effects
			(font
				(size 1.27 1.27)
			)
			(justify left bottom)
		)
	)
	(label "HDMI.D0_N"
		(at 267.97 129.54 0)
		(effects
			(font
				(size 1.27 1.27)
			)
			(justify left bottom)
		)
	)
	(label "GBE_RGMII.MDC"
		(at 234.95 180.34 0)
		(effects
			(font
				(size 1.27 1.27)
			)
			(justify left bottom)
		)
	)
	(label "GBE_RGMII.TXD1"
		(at 234.95 121.92 0)
		(effects
			(font
				(size 1.27 1.27)
			)
			(justify left bottom)
		)
	)
	(label "HDMI.D2_N"
		(at 267.97 210.82 0)
		(effects
			(font
				(size 1.27 1.27)
			)
			(justify left bottom)
		)
	)
	(label "HDMI.D2_P"
		(at 267.97 208.28 0)
		(effects
			(font
				(size 1.27 1.27)
			)
			(justify left bottom)
		)
	)
	(label "GBE_RGMII.MDIO"
		(at 234.95 154.94 0)
		(effects
			(font
				(size 1.27 1.27)
			)
			(justify left bottom)
		)
	)
	(label "USER_IO.B31"
		(at 176.53 195.58 180)
		(effects
			(font
				(size 1.27 1.27)
			)
			(justify right bottom)
		)
	)
	(label "USB_HOST.MOSI"
		(at 300.99 172.72 0)
		(effects
			(font
				(size 1.27 1.27)
			)
			(justify left bottom)
		)
	)
	(label "USER_IO.B26"
		(at 176.53 149.86 180)
		(effects
			(font
				(size 1.27 1.27)
			)
			(justify right bottom)
		)
	)
	(label "USER_IO.B18"
		(at 176.53 127 180)
		(effects
			(font
				(size 1.27 1.27)
			)
			(justify right bottom)
		)
	)
	(label "HDMI.D1_P"
		(at 267.97 182.88 0)
		(effects
			(font
				(size 1.27 1.27)
			)
			(justify left bottom)
		)
	)
	(label "GBE_RGMII.TXD2"
		(at 234.95 142.24 0)
		(effects
			(font
				(size 1.27 1.27)
			)
			(justify left bottom)
		)
	)
	(label "USER_IO.B21"
		(at 176.53 190.5 180)
		(effects
			(font
				(size 1.27 1.27)
			)
			(justify right bottom)
		)
	)
	(label "USER_IO.B19"
		(at 176.53 200.66 180)
		(effects
			(font
				(size 1.27 1.27)
			)
			(justify right bottom)
		)
	)
	(label "GBE_RGMII.RXD0"
		(at 234.95 177.8 0)
		(effects
			(font
				(size 1.27 1.27)
			)
			(justify left bottom)
		)
	)
	(label "USR_FLASH_1.DQ0"
		(at 149.86 157.48 180)
		(effects
			(font
				(size 1.27 1.27)
			)
			(justify right bottom)
		)
	)
	(label "GBE_RGMII.TXD0"
		(at 234.95 139.7 0)
		(effects
			(font
				(size 1.27 1.27)
			)
			(justify left bottom)
		)
	)
	(label "HDMI.D1_N"
		(at 267.97 185.42 0)
		(effects
			(font
				(size 1.27 1.27)
			)
			(justify left bottom)
		)
	)
	(label "HDMI.D0_P"
		(at 267.97 127 0)
		(effects
			(font
				(size 1.27 1.27)
			)
			(justify left bottom)
		)
	)
	(label "USER_IO.B28"
		(at 176.53 180.34 180)
		(effects
			(font
				(size 1.27 1.27)
			)
			(justify right bottom)
		)
	)
	(label "USER_IO.B5"
		(at 176.53 185.42 180)
		(effects
			(font
				(size 1.27 1.27)
			)
			(justify right bottom)
		)
	)
	(label "USR_FLASH_1.~{CS}"
		(at 149.86 162.56 180)
		(effects
			(font
				(size 1.27 1.27)
			)
			(justify right bottom)
		)
	)
	(label "USER_IO.B7"
		(at 176.53 177.8 180)
		(effects
			(font
				(size 1.27 1.27)
			)
			(justify right bottom)
		)
	)
	(label "GBE_RGMII.GTX_CLK"
		(at 234.95 96.52 0)
		(effects
			(font
				(size 1.27 1.27)
			)
			(justify left bottom)
		)
	)
	(label "GBE_RGMII.~{RESET}"
		(at 234.95 160.02 0)
		(effects
			(font
				(size 1.27 1.27)
			)
			(justify left bottom)
		)
	)
	(label "USER_IO.B3"
		(at 176.53 175.26 180)
		(effects
			(font
				(size 1.27 1.27)
			)
			(justify right bottom)
		)
	)
	(label "USER_IO.B27"
		(at 176.53 208.28 180)
		(effects
			(font
				(size 1.27 1.27)
			)
			(justify right bottom)
		)
	)
	(label "USB_HOST.MISO"
		(at 300.99 190.5 0)
		(effects
			(font
				(size 1.27 1.27)
			)
			(justify left bottom)
		)
	)
	(label "USER_IO.B15"
		(at 176.53 132.08 180)
		(effects
			(font
				(size 1.27 1.27)
			)
			(justify right bottom)
		)
	)
	(label "GBE_RGMII.GTR_CLK"
		(at 234.95 152.4 0)
		(effects
			(font
				(size 1.27 1.27)
			)
			(justify left bottom)
		)
	)
	(label "USR_FLASH_1.DQ1"
		(at 149.86 205.74 180)
		(effects
			(font
				(size 1.27 1.27)
			)
			(justify right bottom)
		)
	)
	(label "USB_HOST.GPX"
		(at 300.99 200.66 0)
		(effects
			(font
				(size 1.27 1.27)
			)
			(justify left bottom)
		)
	)
	(label "USER_IO.B33"
		(at 176.53 193.04 180)
		(effects
			(font
				(size 1.27 1.27)
			)
			(justify right bottom)
		)
	)
	(label "USER_IO.B9"
		(at 176.53 134.62 180)
		(effects
			(font
				(size 1.27 1.27)
			)
			(justify right bottom)
		)
	)
	(label "USER_IO.B29"
		(at 176.53 182.88 180)
		(effects
			(font
				(size 1.27 1.27)
			)
			(justify right bottom)
		)
	)
	(label "GBE_RGMII.TXD3"
		(at 234.95 144.78 0)
		(effects
			(font
				(size 1.27 1.27)
			)
			(justify left bottom)
		)
	)
	(label "GBE_RGMII.~{INT}"
		(at 234.95 170.18 0)
		(effects
			(font
				(size 1.27 1.27)
			)
			(justify left bottom)
		)
	)
	(label "USER_IO.B14"
		(at 176.53 147.32 180)
		(effects
			(font
				(size 1.27 1.27)
			)
			(justify right bottom)
		)
	)
	(label "FMC.PRSNT_M2C"
		(at 257.81 109.22 0)
		(effects
			(font
				(size 1.27 1.27)
			)
			(justify left bottom)
		)
	)
	(label "USER_IO.B1"
		(at 176.53 152.4 180)
		(effects
			(font
				(size 1.27 1.27)
			)
			(justify right bottom)
		)
	)
	(label "USER_IO.B25"
		(at 176.53 210.82 180)
		(effects
			(font
				(size 1.27 1.27)
			)
			(justify right bottom)
		)
	)
	(label "USR_FLASH_1.DQ3"
		(at 149.86 165.1 180)
		(effects
			(font
				(size 1.27 1.27)
			)
			(justify right bottom)
		)
	)
	(label "GBE_RGMII.RXD2"
		(at 234.95 147.32 0)
		(effects
			(font
				(size 1.27 1.27)
			)
			(justify left bottom)
		)
	)
	(label "USER_IO.B6"
		(at 176.53 144.78 180)
		(effects
			(font
				(size 1.27 1.27)
			)
			(justify right bottom)
		)
	)
	(hierarchical_label "HDMI{HDMI}"
		(shape bidirectional)
		(at 293.37 215.9 0)
		(effects
			(font
				(size 1.27 1.27)
			)
			(justify left)
		)
	)
	(hierarchical_label "USR_FLASH_1{SPI-FLASH}"
		(shape bidirectional)
		(at 120.65 151.13 180)
		(effects
			(font
				(size 1.27 1.27)
			)
			(justify right)
		)
	)
	(hierarchical_label "USER_IO{USER-IO}"
		(shape bidirectional)
		(at 130.81 87.63 180)
		(effects
			(font
				(size 1.27 1.27)
			)
			(justify right)
		)
	)
	(hierarchical_label "GBE_RGMII{RGMII}"
		(shape bidirectional)
		(at 259.08 81.28 0)
		(effects
			(font
				(size 1.27 1.27)
			)
			(justify left)
		)
	)
	(hierarchical_label "USB_HOST{SPI-USB}"
		(shape bidirectional)
		(at 325.12 160.02 0)
		(effects
			(font
				(size 1.27 1.27)
			)
			(justify left)
		)
	)
	(hierarchical_label "FMC{FMC-CTRL}"
		(shape bidirectional)
		(at 280.67 81.28 0)
		(effects
			(font
				(size 1.27 1.27)
			)
			(justify left)
		)
	)
	(symbol
		(lib_id "antmicroCapacitors0402:C_100n_0402")
		(at 261.62 67.31 90)
		(unit 1)
		(exclude_from_sim no)
		(in_bom yes)
		(on_board yes)
		(dnp no)
		(property "Reference" "C81"
			(at 262.255 62.865 90)
			(effects
				(font
					(size 1.27 1.27)
				)
				(justify right)
			)
		)
		(property "Value" "C_100n_0402"
			(at 271.78 46.99 0)
			(effects
				(font
					(size 1.27 1.27)
					(thickness 0.15)
				)
				(justify left bottom)
				(hide yes)
			)
		)
		(property "Footprint" "antmicro-footprints:C_0402_1005Metric"
			(at 274.32 46.99 0)
			(effects
				(font
					(size 1.27 1.27)
					(thickness 0.15)
				)
				(justify left bottom)
				(hide yes)
			)
		)
		(property "Datasheet" "https://www.murata.com/products/productdetail?partno=GRM155R61H104KE14%23"
			(at 276.86 46.99 0)
			(effects
				(font
					(size 1.27 1.27)
					(thickness 0.15)
				)
				(justify left bottom)
				(hide yes)
			)
		)
		(property "Description" ""
			(at 261.62 67.31 0)
			(effects
				(font
					(size 1.27 1.27)
				)
			)
		)
		(property "Manufacturer" "Murata"
			(at 281.94 46.99 0)
			(effects
				(font
					(size 1.27 1.27)
					(thickness 0.15)
				)
				(justify left bottom)
				(hide yes)
			)
		)
		(property "MPN" "GRM155R61H104KE14D"
			(at 279.4 46.99 0)
			(effects
				(font
					(size 1.27 1.27)
					(thickness 0.15)
				)
				(justify left bottom)
				(hide yes)
			)
		)
		(property "Val" "100n"
			(at 262.255 66.675 90)
			(effects
				(font
					(size 1.27 1.27)
					(thickness 0.15)
				)
				(justify right)
			)
		)
		(property "License" "Apache-2.0"
			(at 284.48 46.99 0)
			(effects
				(font
					(size 1.27 1.27)
					(thickness 0.15)
				)
				(justify left bottom)
				(hide yes)
			)
		)
		(property "Author" "Antmicro"
			(at 287.02 46.99 0)
			(effects
				(font
					(size 1.27 1.27)
					(thickness 0.15)
				)
				(justify left bottom)
				(hide yes)
			)
		)
		(property "Voltage" "50V"
			(at 289.56 46.99 0)
			(effects
				(font
					(size 1.27 1.27)
				)
				(justify left bottom)
				(hide yes)
			)
		)
		(property "Dielectric" "X5R"
			(at 292.1 46.99 0)
			(effects
				(font
					(size 1.27 1.27)
				)
				(justify left bottom)
				(hide yes)
			)
		)
		(pin "1"
		)
		(pin "2"
		)
		(instances
			(project "k410t-devboard"
				(path ""
					(reference "C81")
					(unit 1)
				)
			)
		)
	)
	(symbol
		(lib_id "antmicropower:VCC_USR_B")
		(at 113.03 57.15 0)
		(unit 1)
		(exclude_from_sim no)
		(in_bom yes)
		(on_board yes)
		(dnp no)
		(fields_autoplaced yes)
		(property "Reference" "#PWR06"
			(at 113.03 60.96 0)
			(effects
				(font
					(size 1.27 1.27)
				)
				(hide yes)
			)
		)
		(property "Value" "VCC_USR_B"
			(at 113.03 53.34 0)
			(effects
				(font
					(size 1.27 1.27)
				)
			)
		)
		(property "Footprint" ""
			(at 113.03 57.15 0)
			(effects
				(font
					(size 1.27 1.27)
				)
				(hide yes)
			)
		)
		(property "Datasheet" ""
			(at 113.03 57.15 0)
			(effects
				(font
					(size 1.27 1.27)
				)
				(hide yes)
			)
		)
		(property "Description" ""
			(at 113.03 57.15 0)
			(effects
				(font
					(size 1.27 1.27)
				)
			)
		)
		(pin "1"
		)
		(instances
			(project "k410t-devboard"
				(path ""
					(reference "#PWR06")
					(unit 1)
				)
			)
		)
	)
	(symbol
		(lib_id "antmicroCapacitors0402:C_100n_0402")
		(at 154.94 67.31 90)
		(unit 1)
		(exclude_from_sim no)
		(in_bom yes)
		(on_board yes)
		(dnp no)
		(property "Reference" "C39"
			(at 155.575 62.865 90)
			(effects
				(font
					(size 1.27 1.27)
				)
				(justify right)
			)
		)
		(property "Value" "C_100n_0402"
			(at 165.1 46.99 0)
			(effects
				(font
					(size 1.27 1.27)
					(thickness 0.15)
				)
				(justify left bottom)
				(hide yes)
			)
		)
		(property "Footprint" "antmicro-footprints:C_0402_1005Metric"
			(at 167.64 46.99 0)
			(effects
				(font
					(size 1.27 1.27)
					(thickness 0.15)
				)
				(justify left bottom)
				(hide yes)
			)
		)
		(property "Datasheet" "https://www.murata.com/products/productdetail?partno=GRM155R61H104KE14%23"
			(at 170.18 46.99 0)
			(effects
				(font
					(size 1.27 1.27)
					(thickness 0.15)
				)
				(justify left bottom)
				(hide yes)
			)
		)
		(property "Description" ""
			(at 154.94 67.31 0)
			(effects
				(font
					(size 1.27 1.27)
				)
			)
		)
		(property "Manufacturer" "Murata"
			(at 175.26 46.99 0)
			(effects
				(font
					(size 1.27 1.27)
					(thickness 0.15)
				)
				(justify left bottom)
				(hide yes)
			)
		)
		(property "MPN" "GRM155R61H104KE14D"
			(at 172.72 46.99 0)
			(effects
				(font
					(size 1.27 1.27)
					(thickness 0.15)
				)
				(justify left bottom)
				(hide yes)
			)
		)
		(property "Val" "100n"
			(at 155.575 66.675 90)
			(effects
				(font
					(size 1.27 1.27)
					(thickness 0.15)
				)
				(justify right)
			)
		)
		(property "License" "Apache-2.0"
			(at 177.8 46.99 0)
			(effects
				(font
					(size 1.27 1.27)
					(thickness 0.15)
				)
				(justify left bottom)
				(hide yes)
			)
		)
		(property "Author" "Antmicro"
			(at 180.34 46.99 0)
			(effects
				(font
					(size 1.27 1.27)
					(thickness 0.15)
				)
				(justify left bottom)
				(hide yes)
			)
		)
		(property "Voltage" "50V"
			(at 182.88 46.99 0)
			(effects
				(font
					(size 1.27 1.27)
				)
				(justify left bottom)
				(hide yes)
			)
		)
		(property "Dielectric" "X5R"
			(at 185.42 46.99 0)
			(effects
				(font
					(size 1.27 1.27)
				)
				(justify left bottom)
				(hide yes)
			)
		)
		(pin "1"
		)
		(pin "2"
		)
		(instances
			(project "k410t-devboard"
				(path ""
					(reference "C39")
					(unit 1)
				)
			)
		)
	)
	(symbol
		(lib_id "antmicropower:GND")
		(at 116.84 71.12 0)
		(unit 1)
		(exclude_from_sim no)
		(in_bom yes)
		(on_board yes)
		(dnp no)
		(property "Reference" "#PWR017"
			(at 116.84 77.47 0)
			(effects
				(font
					(size 1.27 1.27)
				)
				(hide yes)
			)
		)
		(property "Value" "GND"
			(at 116.84 74.93 0)
			(effects
				(font
					(size 1.27 1.27)
				)
			)
		)
		(property "Footprint" ""
			(at 125.73 78.74 0)
			(effects
				(font
					(size 1.27 1.27)
					(thickness 0.15)
				)
				(justify left bottom)
				(hide yes)
			)
		)
		(property "Datasheet" ""
			(at 125.73 83.82 0)
			(effects
				(font
					(size 1.27 1.27)
					(thickness 0.15)
				)
				(justify left bottom)
				(hide yes)
			)
		)
		(property "Description" ""
			(at 116.84 71.12 0)
			(effects
				(font
					(size 1.27 1.27)
				)
			)
		)
		(property "Author" "Antmicro"
			(at 125.73 78.74 0)
			(effects
				(font
					(size 1.27 1.27)
					(thickness 0.15)
				)
				(justify left bottom)
				(hide yes)
			)
		)
		(property "License" "Apache-2.0"
			(at 125.73 81.28 0)
			(effects
				(font
					(size 1.27 1.27)
					(thickness 0.15)
				)
				(justify left bottom)
				(hide yes)
			)
		)
		(pin "1"
		)
		(instances
			(project "k410t-devboard"
				(path ""
					(reference "#PWR017")
					(unit 1)
				)
			)
		)
	)
	(symbol
		(lib_id "antmicropower:GND")
		(at 292.1 71.12 0)
		(mirror y)
		(unit 1)
		(exclude_from_sim no)
		(in_bom yes)
		(on_board yes)
		(dnp no)
		(property "Reference" "#PWR020"
			(at 292.1 77.47 0)
			(effects
				(font
					(size 1.27 1.27)
				)
				(hide yes)
			)
		)
		(property "Value" "GND"
			(at 292.1 74.93 0)
			(effects
				(font
					(size 1.27 1.27)
				)
			)
		)
		(property "Footprint" ""
			(at 283.21 78.74 0)
			(effects
				(font
					(size 1.27 1.27)
					(thickness 0.15)
				)
				(justify left bottom)
				(hide yes)
			)
		)
		(property "Datasheet" ""
			(at 283.21 83.82 0)
			(effects
				(font
					(size 1.27 1.27)
					(thickness 0.15)
				)
				(justify left bottom)
				(hide yes)
			)
		)
		(property "Description" ""
			(at 292.1 71.12 0)
			(effects
				(font
					(size 1.27 1.27)
				)
			)
		)
		(property "Author" "Antmicro"
			(at 283.21 78.74 0)
			(effects
				(font
					(size 1.27 1.27)
					(thickness 0.15)
				)
				(justify left bottom)
				(hide yes)
			)
		)
		(property "License" "Apache-2.0"
			(at 283.21 81.28 0)
			(effects
				(font
					(size 1.27 1.27)
					(thickness 0.15)
				)
				(justify left bottom)
				(hide yes)
			)
		)
		(pin "1"
		)
		(instances
			(project "k410t-devboard"
				(path ""
					(reference "#PWR020")
					(unit 1)
				)
			)
		)
	)
	(symbol
		(lib_name "XC7K410T-2FFG900I_1")
		(lib_id "antmicroFPGAChips:XC7K410T-2FFG900I")
		(at 179.07 85.09 0)
		(unit 3)
		(exclude_from_sim no)
		(in_bom yes)
		(on_board yes)
		(dnp no)
		(fields_autoplaced yes)
		(property "Reference" "U1"
			(at 206.375 74.93 0)
			(effects
				(font
					(size 1.27 1.27)
					(thickness 0.15)
				)
			)
		)
		(property "Value" "XC7K410T-2FFG900I"
			(at 206.375 77.47 0)
			(effects
				(font
					(size 1.27 1.27)
					(thickness 0.15)
				)
			)
		)
		(property "Footprint" "antmicro-footprints:BGA-900_31x31mm_Layout30x30_P1x1mm_FFG900"
			(at 179.07 58.42 0)
			(effects
				(font
					(size 1.27 1.27)
					(thickness 0.15)
				)
				(justify left bottom)
				(hide yes)
			)
		)
		(property "Datasheet" "https://eu.mouser.com/datasheet/2/903/ds180_7Series_Overview-1591537.pdf"
			(at 179.07 60.96 0)
			(effects
				(font
					(size 1.27 1.27)
					(thickness 0.15)
				)
				(justify left bottom)
				(hide yes)
			)
		)
		(property "Description" ""
			(at 179.07 85.09 0)
			(effects
				(font
					(size 1.27 1.27)
				)
			)
		)
		(property "Manufacturer" "AMD-Xilinx"
			(at 179.07 63.5 0)
			(effects
				(font
					(size 1.27 1.27)
					(thickness 0.15)
				)
				(justify left bottom)
				(hide yes)
			)
		)
		(property "MPN" "XC7K410T-2FFG900I"
			(at 179.07 66.04 0)
			(effects
				(font
					(size 1.27 1.27)
					(thickness 0.15)
				)
				(justify left bottom)
				(hide yes)
			)
		)
		(property "Author" "Antmicro"
			(at 179.07 68.58 0)
			(effects
				(font
					(size 1.27 1.27)
					(thickness 0.15)
				)
				(justify left bottom)
				(hide yes)
			)
		)
		(property "License" "Apache-2.0"
			(at 179.07 71.12 0)
			(effects
				(font
					(size 1.27 1.27)
					(thickness 0.15)
				)
				(justify left bottom)
				(hide yes)
			)
		)
		(pin "A23"
		)
		(pin "A25"
		)
		(pin "A26"
		)
		(pin "A27"
		)
		(pin "A28"
		)
		(pin "A30"
		)
		(pin "B23"
		)
		(pin "B24"
		)
		(pin "B25"
		)
		(pin "B27"
		)
		(pin "B28"
		)
		(pin "B29"
		)
		(pin "B30"
		)
		(pin "C24"
		)
		(pin "C25"
		)
		(pin "C26"
		)
		(pin "C27"
		)
		(pin "C29"
		)
		(pin "C30"
		)
		(pin "D23"
		)
		(pin "D24"
		)
		(pin "D26"
		)
		(pin "D27"
		)
		(pin "D28"
		)
		(pin "D29"
		)
		(pin "E23"
		)
		(pin "E24"
		)
		(pin "E25"
		)
		(pin "E26"
		)
		(pin "E28"
		)
		(pin "E29"
		)
		(pin "E30"
		)
		(pin "F23"
		)
		(pin "F25"
		)
		(pin "F26"
		)
		(pin "F27"
		)
		(pin "F28"
		)
		(pin "F30"
		)
		(pin "G23"
		)
		(pin "G24"
		)
		(pin "G25"
		)
		(pin "G27"
		)
		(pin "G28"
		)
		(pin "G29"
		)
		(pin "G30"
		)
		(pin "H24"
		)
		(pin "H25"
		)
		(pin "H26"
		)
		(pin "H27"
		)
		(pin "H30"
		)
		(pin "AA22"
		)
		(pin "AA23"
		)
		(pin "AB20"
		)
		(pin "AB22"
		)
		(pin "AB23"
		)
		(pin "AB24"
		)
		(pin "AC20"
		)
		(pin "AC21"
		)
		(pin "AC22"
		)
		(pin "AC24"
		)
		(pin "AC25"
		)
		(pin "AD21"
		)
		(pin "AD22"
		)
		(pin "AD23"
		)
		(pin "AD24"
		)
		(pin "AE20"
		)
		(pin "AE21"
		)
		(pin "AE23"
		)
		(pin "AE24"
		)
		(pin "AE25"
		)
		(pin "AF20"
		)
		(pin "AF21"
		)
		(pin "AF22"
		)
		(pin "AF23"
		)
		(pin "AF25"
		)
		(pin "AG20"
		)
		(pin "AG22"
		)
		(pin "AG23"
		)
		(pin "AG24"
		)
		(pin "AG25"
		)
		(pin "AH20"
		)
		(pin "AH21"
		)
		(pin "AH22"
		)
		(pin "AH24"
		)
		(pin "AH25"
		)
		(pin "AJ21"
		)
		(pin "AJ22"
		)
		(pin "AJ23"
		)
		(pin "AJ24"
		)
		(pin "AK20"
		)
		(pin "AK21"
		)
		(pin "AK23"
		)
		(pin "AK24"
		)
		(pin "AK25"
		)
		(pin "Y20"
		)
		(pin "Y21"
		)
		(pin "Y23"
		)
		(pin "Y24"
		)
		(pin "P24"
		)
		(pin "P26"
		)
		(pin "P27"
		)
		(pin "P28"
		)
		(pin "P29"
		)
		(pin "R19"
		)
		(pin "R20"
		)
		(pin "R21"
		)
		(pin "R23"
		)
		(pin "R24"
		)
		(pin "R25"
		)
		(pin "R26"
		)
		(pin "R28"
		)
		(pin "R29"
		)
		(pin "R30"
		)
		(pin "T20"
		)
		(pin "T21"
		)
		(pin "T22"
		)
		(pin "T23"
		)
		(pin "T25"
		)
		(pin "T26"
		)
		(pin "T27"
		)
		(pin "T28"
		)
		(pin "T30"
		)
		(pin "U19"
		)
		(pin "U20"
		)
		(pin "U22"
		)
		(pin "U23"
		)
		(pin "U24"
		)
		(pin "U25"
		)
		(pin "U27"
		)
		(pin "U28"
		)
		(pin "U29"
		)
		(pin "U30"
		)
		(pin "V19"
		)
		(pin "V20"
		)
		(pin "V21"
		)
		(pin "V22"
		)
		(pin "V24"
		)
		(pin "V25"
		)
		(pin "V26"
		)
		(pin "V27"
		)
		(pin "V29"
		)
		(pin "V30"
		)
		(pin "W19"
		)
		(pin "W21"
		)
		(pin "W22"
		)
		(pin "W23"
		)
		(pin "W24"
		)
		(pin "W26"
		)
		(pin "B2"
		)
		(pin "B5"
		)
		(pin "B6"
		)
		(pin "C3"
		)
		(pin "C4"
		)
		(pin "A11"
		)
		(pin "A12"
		)
		(pin "A13"
		)
		(pin "A15"
		)
		(pin "B12"
		)
		(pin "B13"
		)
		(pin "B14"
		)
		(pin "B15"
		)
		(pin "C11"
		)
		(pin "C12"
		)
		(pin "C14"
		)
		(pin "C15"
		)
		(pin "D11"
		)
		(pin "D12"
		)
		(pin "D13"
		)
		(pin "D14"
		)
		(pin "E11"
		)
		(pin "E13"
		)
		(pin "E14"
		)
		(pin "E15"
		)
		(pin "E16"
		)
		(pin "F11"
		)
		(pin "F12"
		)
		(pin "F13"
		)
		(pin "F15"
		)
		(pin "F16"
		)
		(pin "G12"
		)
		(pin "G13"
		)
		(pin "G14"
		)
		(pin "G15"
		)
		(pin "H11"
		)
		(pin "H12"
		)
		(pin "H14"
		)
		(pin "H15"
		)
		(pin "H16"
		)
		(pin "J11"
		)
		(pin "J12"
		)
		(pin "J13"
		)
		(pin "J14"
		)
		(pin "J16"
		)
		(pin "K11"
		)
		(pin "K13"
		)
		(pin "K14"
		)
		(pin "K15"
		)
		(pin "K16"
		)
		(pin "L11"
		)
		(pin "L12"
		)
		(pin "L13"
		)
		(pin "L15"
		)
		(pin "L16"
		)
		(pin "AA10"
		)
		(pin "AA11"
		)
		(pin "AA12"
		)
		(pin "AA13"
		)
		(pin "AA8"
		)
		(pin "AB10"
		)
		(pin "AB12"
		)
		(pin "AB13"
		)
		(pin "AB8"
		)
		(pin "AB9"
		)
		(pin "AC10"
		)
		(pin "AC11"
		)
		(pin "AC12"
		)
		(pin "AC9"
		)
		(pin "AD11"
		)
		(pin "AD12"
		)
		(pin "AD13"
		)
		(pin "AD8"
		)
		(pin "AD9"
		)
		(pin "AE10"
		)
		(pin "AE11"
		)
		(pin "AE13"
		)
		(pin "AE8"
		)
		(pin "AE9"
		)
		(pin "AF10"
		)
		(pin "AF11"
		)
		(pin "AF12"
		)
		(pin "AF13"
		)
		(pin "AG10"
		)
		(pin "AG12"
		)
		(pin "AG13"
		)
		(pin "AG9"
		)
		(pin "AH10"
		)
		(pin "AH11"
		)
		(pin "AH12"
		)
		(pin "AH14"
		)
		(pin "AH9"
		)
		(pin "AJ11"
		)
		(pin "AJ12"
		)
		(pin "AJ13"
		)
		(pin "AJ14"
		)
		(pin "AJ9"
		)
		(pin "AK10"
		)
		(pin "AK11"
		)
		(pin "AK13"
		)
		(pin "AK14"
		)
		(pin "AK9"
		)
		(pin "Y10"
		)
		(pin "Y11"
		)
		(pin "Y13"
		)
		(pin "A3"
		)
		(pin "A4"
		)
		(pin "A7"
		)
		(pin "A8"
		)
		(pin "AA3"
		)
		(pin "AA4"
		)
		(pin "B1"
		)
		(pin "G16"
		)
		(pin "G2"
		)
		(pin "G26"
		)
		(pin "G6"
		)
		(pin "G9"
		)
		(pin "H13"
		)
		(pin "H23"
		)
		(pin "H4"
		)
		(pin "H8"
		)
		(pin "H9"
		)
		(pin "J1"
		)
		(pin "J10"
		)
		(pin "C7"
		)
		(pin "C8"
		)
		(pin "D1"
		)
		(pin "D2"
		)
		(pin "D5"
		)
		(pin "D6"
		)
		(pin "E3"
		)
		(pin "E4"
		)
		(pin "E7"
		)
		(pin "E8"
		)
		(pin "F1"
		)
		(pin "F2"
		)
		(pin "F5"
		)
		(pin "F6"
		)
		(pin "G3"
		)
		(pin "G4"
		)
		(pin "G7"
		)
		(pin "G8"
		)
		(pin "H1"
		)
		(pin "H2"
		)
		(pin "H5"
		)
		(pin "H6"
		)
		(pin "J3"
		)
		(pin "J4"
		)
		(pin "J7"
		)
		(pin "J8"
		)
		(pin "K1"
		)
		(pin "K2"
		)
		(pin "K5"
		)
		(pin "K6"
		)
		(pin "L3"
		)
		(pin "L4"
		)
		(pin "L7"
		)
		(pin "L8"
		)
		(pin "M1"
		)
		(pin "M2"
		)
		(pin "M5"
		)
		(pin "M6"
		)
		(pin "N3"
		)
		(pin "N4"
		)
		(pin "N7"
		)
		(pin "N8"
		)
		(pin "P1"
		)
		(pin "P2"
		)
		(pin "P5"
		)
		(pin "P6"
		)
		(pin "R3"
		)
		(pin "R4"
		)
		(pin "R7"
		)
		(pin "R8"
		)
		(pin "T1"
		)
		(pin "T2"
		)
		(pin "T5"
		)
		(pin "T6"
		)
		(pin "U3"
		)
		(pin "U4"
		)
		(pin "U7"
		)
		(pin "U8"
		)
		(pin "V1"
		)
		(pin "V2"
		)
		(pin "V5"
		)
		(pin "V6"
		)
		(pin "W3"
		)
		(pin "W4"
		)
		(pin "Y1"
		)
		(pin "Y2"
		)
		(pin "Y5"
		)
		(pin "Y6"
		)
		(pin "B3"
		)
		(pin "B7"
		)
		(pin "C5"
		)
		(pin "D3"
		)
		(pin "D7"
		)
		(pin "E5"
		)
		(pin "F3"
		)
		(pin "F7"
		)
		(pin "G5"
		)
		(pin "H3"
		)
		(pin "H7"
		)
		(pin "J5"
		)
		(pin "K3"
		)
		(pin "K7"
		)
		(pin "L5"
		)
		(pin "M3"
		)
		(pin "M7"
		)
		(pin "N5"
		)
		(pin "P3"
		)
		(pin "P7"
		)
		(pin "R5"
		)
		(pin "T3"
		)
		(pin "T7"
		)
		(pin "U5"
		)
		(pin "V3"
		)
		(pin "V7"
		)
		(pin "W5"
		)
		(pin "W7"
		)
		(pin "W8"
		)
		(pin "A10"
		)
		(pin "AB1"
		)
		(pin "AB2"
		)
		(pin "AB5"
		)
		(pin "B10"
		)
		(pin "E10"
		)
		(pin "F10"
		)
		(pin "G10"
		)
		(pin "H10"
		)
		(pin "K10"
		)
		(pin "L10"
		)
		(pin "M10"
		)
		(pin "R14"
		)
		(pin "R15"
		)
		(pin "T14"
		)
		(pin "T15"
		)
		(pin "U14"
		)
		(pin "U15"
		)
		(pin "A19"
		)
		(pin "A29"
		)
		(pin "AA19"
		)
		(pin "AA29"
		)
		(pin "AA9"
		)
		(pin "AB16"
		)
		(pin "AB26"
		)
		(pin "AB6"
		)
		(pin "AC13"
		)
		(pin "AC23"
		)
		(pin "AC3"
		)
		(pin "AD10"
		)
		(pin "AD20"
		)
		(pin "AD30"
		)
		(pin "AE17"
		)
		(pin "AE27"
		)
		(pin "AE7"
		)
		(pin "AF14"
		)
		(pin "AF24"
		)
		(pin "AF4"
		)
		(pin "AG1"
		)
		(pin "AG11"
		)
		(pin "AG21"
		)
		(pin "AH18"
		)
		(pin "AH28"
		)
		(pin "AH8"
		)
		(pin "AJ15"
		)
		(pin "AJ25"
		)
		(pin "AJ5"
		)
		(pin "AK12"
		)
		(pin "AK2"
		)
		(pin "AK22"
		)
		(pin "B16"
		)
		(pin "B26"
		)
		(pin "C13"
		)
		(pin "C23"
		)
		(pin "D10"
		)
		(pin "D20"
		)
		(pin "D30"
		)
		(pin "E17"
		)
		(pin "E27"
		)
		(pin "F14"
		)
		(pin "F24"
		)
		(pin "G11"
		)
		(pin "G21"
		)
		(pin "H18"
		)
		(pin "H28"
		)
		(pin "J15"
		)
		(pin "J25"
		)
		(pin "K12"
		)
		(pin "K22"
		)
		(pin "L19"
		)
		(pin "L29"
		)
		(pin "M26"
		)
		(pin "N23"
		)
		(pin "P20"
		)
		(pin "P30"
		)
		(pin "R27"
		)
		(pin "T24"
		)
		(pin "T9"
		)
		(pin "U21"
		)
		(pin "V28"
		)
		(pin "W25"
		)
		(pin "Y12"
		)
		(pin "Y22"
		)
		(pin "A1"
		)
		(pin "A14"
		)
		(pin "A2"
		)
		(pin "A24"
		)
		(pin "A5"
		)
		(pin "A6"
		)
		(pin "A9"
		)
		(pin "AA1"
		)
		(pin "AA14"
		)
		(pin "AA2"
		)
		(pin "AA24"
		)
		(pin "AA5"
		)
		(pin "AA6"
		)
		(pin "AA7"
		)
		(pin "AB11"
		)
		(pin "AB21"
		)
		(pin "AB3"
		)
		(pin "AB4"
		)
		(pin "AC18"
		)
		(pin "AC28"
		)
		(pin "AC8"
		)
		(pin "AD15"
		)
		(pin "AD25"
		)
		(pin "AD5"
		)
		(pin "AE12"
		)
		(pin "AE2"
		)
		(pin "AE22"
		)
		(pin "AF19"
		)
		(pin "AF29"
		)
		(pin "AF9"
		)
		(pin "AG16"
		)
		(pin "AG26"
		)
		(pin "AG6"
		)
		(pin "AH13"
		)
		(pin "AH23"
		)
		(pin "AH3"
		)
		(pin "AJ10"
		)
		(pin "AJ20"
		)
		(pin "AJ30"
		)
		(pin "AK17"
		)
		(pin "AK27"
		)
		(pin "AK7"
		)
		(pin "B11"
		)
		(pin "B21"
		)
		(pin "B4"
		)
		(pin "B8"
		)
		(pin "B9"
		)
		(pin "C1"
		)
		(pin "C10"
		)
		(pin "C18"
		)
		(pin "C2"
		)
		(pin "C28"
		)
		(pin "C6"
		)
		(pin "C9"
		)
		(pin "D15"
		)
		(pin "D25"
		)
		(pin "D4"
		)
		(pin "D8"
		)
		(pin "D9"
		)
		(pin "E1"
		)
		(pin "E12"
		)
		(pin "E2"
		)
		(pin "E22"
		)
		(pin "E6"
		)
		(pin "E9"
		)
		(pin "F19"
		)
		(pin "F29"
		)
		(pin "F4"
		)
		(pin "F8"
		)
		(pin "F9"
		)
		(pin "G1"
		)
		(pin "J2"
		)
		(pin "J20"
		)
		(pin "J30"
		)
		(pin "J6"
		)
		(pin "J9"
		)
		(pin "K17"
		)
		(pin "K27"
		)
		(pin "K4"
		)
		(pin "K8"
		)
		(pin "K9"
		)
		(pin "L1"
		)
		(pin "L14"
		)
		(pin "L2"
		)
		(pin "L24"
		)
		(pin "L6"
		)
		(pin "L9"
		)
		(pin "M11"
		)
		(pin "M12"
		)
		(pin "M13"
		)
		(pin "M14"
		)
		(pin "M15"
		)
		(pin "M16"
		)
		(pin "M17"
		)
		(pin "M18"
		)
		(pin "M21"
		)
		(pin "M4"
		)
		(pin "M8"
		)
		(pin "M9"
		)
		(pin "N1"
		)
		(pin "N10"
		)
		(pin "N11"
		)
		(pin "N12"
		)
		(pin "N13"
		)
		(pin "N14"
		)
		(pin "N15"
		)
		(pin "N16"
		)
		(pin "N17"
		)
		(pin "N18"
		)
		(pin "N2"
		)
		(pin "N28"
		)
		(pin "N6"
		)
		(pin "N9"
		)
		(pin "P10"
		)
		(pin "P11"
		)
		(pin "P12"
		)
		(pin "P13"
		)
		(pin "P14"
		)
		(pin "P15"
		)
		(pin "P16"
		)
		(pin "P17"
		)
		(pin "P18"
		)
		(pin "P25"
		)
		(pin "P4"
		)
		(pin "P8"
		)
		(pin "P9"
		)
		(pin "R1"
		)
		(pin "R10"
		)
		(pin "R11"
		)
		(pin "R12"
		)
		(pin "R13"
		)
		(pin "R16"
		)
		(pin "R17"
		)
		(pin "R18"
		)
		(pin "R2"
		)
		(pin "R22"
		)
		(pin "R6"
		)
		(pin "R9"
		)
		(pin "T10"
		)
		(pin "T11"
		)
		(pin "T12"
		)
		(pin "T13"
		)
		(pin "T16"
		)
		(pin "T17"
		)
		(pin "T18"
		)
		(pin "T19"
		)
		(pin "T29"
		)
		(pin "T4"
		)
		(pin "T8"
		)
		(pin "U1"
		)
		(pin "U10"
		)
		(pin "U11"
		)
		(pin "U12"
		)
		(pin "U13"
		)
		(pin "U16"
		)
		(pin "U17"
		)
		(pin "U18"
		)
		(pin "U2"
		)
		(pin "U26"
		)
		(pin "U6"
		)
		(pin "U9"
		)
		(pin "V10"
		)
		(pin "V11"
		)
		(pin "V12"
		)
		(pin "V13"
		)
		(pin "V14"
		)
		(pin "V15"
		)
		(pin "V16"
		)
		(pin "V17"
		)
		(pin "V18"
		)
		(pin "V23"
		)
		(pin "V4"
		)
		(pin "V8"
		)
		(pin "V9"
		)
		(pin "W1"
		)
		(pin "W10"
		)
		(pin "W11"
		)
		(pin "W12"
		)
		(pin "W13"
		)
		(pin "W14"
		)
		(pin "W15"
		)
		(pin "W16"
		)
		(pin "W17"
		)
		(pin "W18"
		)
		(pin "W2"
		)
		(pin "W20"
		)
		(pin "W30"
		)
		(pin "W6"
		)
		(pin "W9"
		)
		(pin "Y17"
		)
		(pin "Y27"
		)
		(pin "Y3"
		)
		(pin "Y4"
		)
		(pin "Y7"
		)
		(pin "Y8"
		)
		(pin "Y9"
		)
		(pin "AA25"
		)
		(pin "AA26"
		)
		(pin "AA27"
		)
		(pin "AA28"
		)
		(pin "AA30"
		)
		(pin "AB25"
		)
		(pin "AB27"
		)
		(pin "AB28"
		)
		(pin "AB29"
		)
		(pin "AB30"
		)
		(pin "AC26"
		)
		(pin "AC27"
		)
		(pin "AC29"
		)
		(pin "AC30"
		)
		(pin "AD26"
		)
		(pin "AD27"
		)
		(pin "AD28"
		)
		(pin "AD29"
		)
		(pin "AE26"
		)
		(pin "AE28"
		)
		(pin "AE29"
		)
		(pin "AE30"
		)
		(pin "AF26"
		)
		(pin "AF27"
		)
		(pin "AF28"
		)
		(pin "AF30"
		)
		(pin "AG27"
		)
		(pin "AG28"
		)
		(pin "AG29"
		)
		(pin "AG30"
		)
		(pin "AH26"
		)
		(pin "AH27"
		)
		(pin "AH29"
		)
		(pin "AH30"
		)
		(pin "AJ26"
		)
		(pin "AJ27"
		)
		(pin "AJ28"
		)
		(pin "AJ29"
		)
		(pin "AK26"
		)
		(pin "AK28"
		)
		(pin "AK29"
		)
		(pin "AK30"
		)
		(pin "W27"
		)
		(pin "W28"
		)
		(pin "W29"
		)
		(pin "Y25"
		)
		(pin "Y26"
		)
		(pin "Y28"
		)
		(pin "Y29"
		)
		(pin "Y30"
		)
		(pin "H29"
		)
		(pin "J21"
		)
		(pin "J22"
		)
		(pin "J23"
		)
		(pin "J24"
		)
		(pin "J26"
		)
		(pin "J27"
		)
		(pin "J28"
		)
		(pin "J29"
		)
		(pin "K21"
		)
		(pin "K23"
		)
		(pin "K24"
		)
		(pin "K25"
		)
		(pin "K26"
		)
		(pin "K28"
		)
		(pin "K29"
		)
		(pin "K30"
		)
		(pin "L20"
		)
		(pin "L21"
		)
		(pin "L22"
		)
		(pin "L23"
		)
		(pin "L25"
		)
		(pin "L26"
		)
		(pin "L27"
		)
		(pin "L28"
		)
		(pin "L30"
		)
		(pin "M19"
		)
		(pin "M20"
		)
		(pin "M22"
		)
		(pin "M23"
		)
		(pin "M24"
		)
		(pin "M25"
		)
		(pin "M27"
		)
		(pin "M28"
		)
		(pin "M29"
		)
		(pin "M30"
		)
		(pin "N19"
		)
		(pin "N20"
		)
		(pin "N21"
		)
		(pin "N22"
		)
		(pin "N24"
		)
		(pin "N25"
		)
		(pin "N26"
		)
		(pin "N27"
		)
		(pin "N29"
		)
		(pin "N30"
		)
		(pin "P19"
		)
		(pin "P21"
		)
		(pin "P22"
		)
		(pin "P23"
		)
		(pin "A16"
		)
		(pin "A17"
		)
		(pin "A18"
		)
		(pin "A20"
		)
		(pin "A21"
		)
		(pin "A22"
		)
		(pin "B17"
		)
		(pin "B18"
		)
		(pin "B19"
		)
		(pin "B20"
		)
		(pin "B22"
		)
		(pin "C16"
		)
		(pin "C17"
		)
		(pin "C19"
		)
		(pin "C20"
		)
		(pin "C21"
		)
		(pin "C22"
		)
		(pin "D16"
		)
		(pin "D17"
		)
		(pin "D18"
		)
		(pin "D19"
		)
		(pin "D21"
		)
		(pin "D22"
		)
		(pin "E18"
		)
		(pin "E19"
		)
		(pin "E20"
		)
		(pin "E21"
		)
		(pin "F17"
		)
		(pin "F18"
		)
		(pin "F20"
		)
		(pin "F21"
		)
		(pin "F22"
		)
		(pin "G17"
		)
		(pin "G18"
		)
		(pin "G19"
		)
		(pin "G20"
		)
		(pin "G22"
		)
		(pin "H17"
		)
		(pin "H19"
		)
		(pin "H20"
		)
		(pin "H21"
		)
		(pin "H22"
		)
		(pin "J17"
		)
		(pin "J18"
		)
		(pin "J19"
		)
		(pin "K18"
		)
		(pin "K19"
		)
		(pin "K20"
		)
		(pin "L17"
		)
		(pin "L18"
		)
		(pin "AA15"
		)
		(pin "AA16"
		)
		(pin "AA17"
		)
		(pin "AA18"
		)
		(pin "AB14"
		)
		(pin "AB15"
		)
		(pin "AB17"
		)
		(pin "AB18"
		)
		(pin "AB19"
		)
		(pin "AC14"
		)
		(pin "AC15"
		)
		(pin "AC16"
		)
		(pin "AC17"
		)
		(pin "AC19"
		)
		(pin "AD14"
		)
		(pin "AD16"
		)
		(pin "AD17"
		)
		(pin "AD18"
		)
		(pin "AD19"
		)
		(pin "AE14"
		)
		(pin "AE15"
		)
		(pin "AE16"
		)
		(pin "AE18"
		)
		(pin "AE19"
		)
		(pin "AF15"
		)
		(pin "AF16"
		)
		(pin "AF17"
		)
		(pin "AF18"
		)
		(pin "AG14"
		)
		(pin "AG15"
		)
		(pin "AG17"
		)
		(pin "AG18"
		)
		(pin "AG19"
		)
		(pin "AH15"
		)
		(pin "AH16"
		)
		(pin "AH17"
		)
		(pin "AH19"
		)
		(pin "AJ16"
		)
		(pin "AJ17"
		)
		(pin "AJ18"
		)
		(pin "AJ19"
		)
		(pin "AK15"
		)
		(pin "AK16"
		)
		(pin "AK18"
		)
		(pin "AK19"
		)
		(pin "Y14"
		)
		(pin "Y15"
		)
		(pin "Y16"
		)
		(pin "Y18"
		)
		(pin "Y19"
		)
		(pin "AB7"
		)
		(pin "AC1"
		)
		(pin "AC2"
		)
		(pin "AC4"
		)
		(pin "AC5"
		)
		(pin "AC6"
		)
		(pin "AC7"
		)
		(pin "AD1"
		)
		(pin "AD2"
		)
		(pin "AD3"
		)
		(pin "AD4"
		)
		(pin "AD6"
		)
		(pin "AD7"
		)
		(pin "AE1"
		)
		(pin "AE3"
		)
		(pin "AE4"
		)
		(pin "AE5"
		)
		(pin "AE6"
		)
		(pin "AF1"
		)
		(pin "AF2"
		)
		(pin "AF3"
		)
		(pin "AF5"
		)
		(pin "AF6"
		)
		(pin "AF7"
		)
		(pin "AF8"
		)
		(pin "AG2"
		)
		(pin "AG3"
		)
		(pin "AG4"
		)
		(pin "AG5"
		)
		(pin "AG7"
		)
		(pin "AG8"
		)
		(pin "AH1"
		)
		(pin "AH2"
		)
		(pin "AH4"
		)
		(pin "AH5"
		)
		(pin "AH6"
		)
		(pin "AH7"
		)
		(pin "AJ1"
		)
		(pin "AJ2"
		)
		(pin "AJ3"
		)
		(pin "AJ4"
		)
		(pin "AJ6"
		)
		(pin "AJ7"
		)
		(pin "AJ8"
		)
		(pin "AK1"
		)
		(pin "AK3"
		)
		(pin "AK4"
		)
		(pin "AK5"
		)
		(pin "AK6"
		)
		(pin "AK8"
		)
		(pin "AA20"
		)
		(pin "AA21"
		)
		(instances
			(project "k410t-devboard"
				(path ""
					(reference "U1")
					(unit 3)
				)
			)
		)
	)
	(symbol
		(lib_id "antmicroCapacitors0402:C_100n_0402")
		(at 132.08 67.31 90)
		(unit 1)
		(exclude_from_sim no)
		(in_bom yes)
		(on_board yes)
		(dnp no)
		(property "Reference" "C21"
			(at 132.715 62.865 90)
			(effects
				(font
					(size 1.27 1.27)
				)
				(justify right)
			)
		)
		(property "Value" "C_100n_0402"
			(at 142.24 46.99 0)
			(effects
				(font
					(size 1.27 1.27)
					(thickness 0.15)
				)
				(justify left bottom)
				(hide yes)
			)
		)
		(property "Footprint" "antmicro-footprints:C_0402_1005Metric"
			(at 144.78 46.99 0)
			(effects
				(font
					(size 1.27 1.27)
					(thickness 0.15)
				)
				(justify left bottom)
				(hide yes)
			)
		)
		(property "Datasheet" "https://www.murata.com/products/productdetail?partno=GRM155R61H104KE14%23"
			(at 147.32 46.99 0)
			(effects
				(font
					(size 1.27 1.27)
					(thickness 0.15)
				)
				(justify left bottom)
				(hide yes)
			)
		)
		(property "Description" ""
			(at 132.08 67.31 0)
			(effects
				(font
					(size 1.27 1.27)
				)
			)
		)
		(property "Manufacturer" "Murata"
			(at 152.4 46.99 0)
			(effects
				(font
					(size 1.27 1.27)
					(thickness 0.15)
				)
				(justify left bottom)
				(hide yes)
			)
		)
		(property "MPN" "GRM155R61H104KE14D"
			(at 149.86 46.99 0)
			(effects
				(font
					(size 1.27 1.27)
					(thickness 0.15)
				)
				(justify left bottom)
				(hide yes)
			)
		)
		(property "Val" "100n"
			(at 132.715 66.675 90)
			(effects
				(font
					(size 1.27 1.27)
					(thickness 0.15)
				)
				(justify right)
			)
		)
		(property "License" "Apache-2.0"
			(at 154.94 46.99 0)
			(effects
				(font
					(size 1.27 1.27)
					(thickness 0.15)
				)
				(justify left bottom)
				(hide yes)
			)
		)
		(property "Author" "Antmicro"
			(at 157.48 46.99 0)
			(effects
				(font
					(size 1.27 1.27)
					(thickness 0.15)
				)
				(justify left bottom)
				(hide yes)
			)
		)
		(property "Voltage" "50V"
			(at 160.02 46.99 0)
			(effects
				(font
					(size 1.27 1.27)
				)
				(justify left bottom)
				(hide yes)
			)
		)
		(property "Dielectric" "X5R"
			(at 162.56 46.99 0)
			(effects
				(font
					(size 1.27 1.27)
				)
				(justify left bottom)
				(hide yes)
			)
		)
		(pin "1"
		)
		(pin "2"
		)
		(instances
			(project "k410t-devboard"
				(path ""
					(reference "C21")
					(unit 1)
				)
			)
		)
	)
	(symbol
		(lib_id "antmicroCapacitors0402:C_100n_0402")
		(at 238.76 67.31 90)
		(unit 1)
		(exclude_from_sim no)
		(in_bom yes)
		(on_board yes)
		(dnp no)
		(property "Reference" "C61"
			(at 239.395 62.865 90)
			(effects
				(font
					(size 1.27 1.27)
				)
				(justify right)
			)
		)
		(property "Value" "C_100n_0402"
			(at 248.92 46.99 0)
			(effects
				(font
					(size 1.27 1.27)
					(thickness 0.15)
				)
				(justify left bottom)
				(hide yes)
			)
		)
		(property "Footprint" "antmicro-footprints:C_0402_1005Metric"
			(at 251.46 46.99 0)
			(effects
				(font
					(size 1.27 1.27)
					(thickness 0.15)
				)
				(justify left bottom)
				(hide yes)
			)
		)
		(property "Datasheet" "https://www.murata.com/products/productdetail?partno=GRM155R61H104KE14%23"
			(at 254 46.99 0)
			(effects
				(font
					(size 1.27 1.27)
					(thickness 0.15)
				)
				(justify left bottom)
				(hide yes)
			)
		)
		(property "Description" ""
			(at 238.76 67.31 0)
			(effects
				(font
					(size 1.27 1.27)
				)
			)
		)
		(property "Manufacturer" "Murata"
			(at 259.08 46.99 0)
			(effects
				(font
					(size 1.27 1.27)
					(thickness 0.15)
				)
				(justify left bottom)
				(hide yes)
			)
		)
		(property "MPN" "GRM155R61H104KE14D"
			(at 256.54 46.99 0)
			(effects
				(font
					(size 1.27 1.27)
					(thickness 0.15)
				)
				(justify left bottom)
				(hide yes)
			)
		)
		(property "Val" "100n"
			(at 239.395 66.675 90)
			(effects
				(font
					(size 1.27 1.27)
					(thickness 0.15)
				)
				(justify right)
			)
		)
		(property "License" "Apache-2.0"
			(at 261.62 46.99 0)
			(effects
				(font
					(size 1.27 1.27)
					(thickness 0.15)
				)
				(justify left bottom)
				(hide yes)
			)
		)
		(property "Author" "Antmicro"
			(at 264.16 46.99 0)
			(effects
				(font
					(size 1.27 1.27)
					(thickness 0.15)
				)
				(justify left bottom)
				(hide yes)
			)
		)
		(property "Voltage" "50V"
			(at 266.7 46.99 0)
			(effects
				(font
					(size 1.27 1.27)
				)
				(justify left bottom)
				(hide yes)
			)
		)
		(property "Dielectric" "X5R"
			(at 269.24 46.99 0)
			(effects
				(font
					(size 1.27 1.27)
				)
				(justify left bottom)
				(hide yes)
			)
		)
		(pin "1"
		)
		(pin "2"
		)
		(instances
			(project "k410t-devboard"
				(path ""
					(reference "C61")
					(unit 1)
				)
			)
		)
	)
	(symbol
		(lib_id "antmicroCapacitors0402:C_100n_0402")
		(at 147.32 67.31 90)
		(unit 1)
		(exclude_from_sim no)
		(in_bom yes)
		(on_board yes)
		(dnp no)
		(property "Reference" "C33"
			(at 147.955 62.865 90)
			(effects
				(font
					(size 1.27 1.27)
				)
				(justify right)
			)
		)
		(property "Value" "C_100n_0402"
			(at 157.48 46.99 0)
			(effects
				(font
					(size 1.27 1.27)
					(thickness 0.15)
				)
				(justify left bottom)
				(hide yes)
			)
		)
		(property "Footprint" "antmicro-footprints:C_0402_1005Metric"
			(at 160.02 46.99 0)
			(effects
				(font
					(size 1.27 1.27)
					(thickness 0.15)
				)
				(justify left bottom)
				(hide yes)
			)
		)
		(property "Datasheet" "https://www.murata.com/products/productdetail?partno=GRM155R61H104KE14%23"
			(at 162.56 46.99 0)
			(effects
				(font
					(size 1.27 1.27)
					(thickness 0.15)
				)
				(justify left bottom)
				(hide yes)
			)
		)
		(property "Description" ""
			(at 147.32 67.31 0)
			(effects
				(font
					(size 1.27 1.27)
				)
			)
		)
		(property "Manufacturer" "Murata"
			(at 167.64 46.99 0)
			(effects
				(font
					(size 1.27 1.27)
					(thickness 0.15)
				)
				(justify left bottom)
				(hide yes)
			)
		)
		(property "MPN" "GRM155R61H104KE14D"
			(at 165.1 46.99 0)
			(effects
				(font
					(size 1.27 1.27)
					(thickness 0.15)
				)
				(justify left bottom)
				(hide yes)
			)
		)
		(property "Val" "100n"
			(at 147.955 66.675 90)
			(effects
				(font
					(size 1.27 1.27)
					(thickness 0.15)
				)
				(justify right)
			)
		)
		(property "License" "Apache-2.0"
			(at 170.18 46.99 0)
			(effects
				(font
					(size 1.27 1.27)
					(thickness 0.15)
				)
				(justify left bottom)
				(hide yes)
			)
		)
		(property "Author" "Antmicro"
			(at 172.72 46.99 0)
			(effects
				(font
					(size 1.27 1.27)
					(thickness 0.15)
				)
				(justify left bottom)
				(hide yes)
			)
		)
		(property "Voltage" "50V"
			(at 175.26 46.99 0)
			(effects
				(font
					(size 1.27 1.27)
				)
				(justify left bottom)
				(hide yes)
			)
		)
		(property "Dielectric" "X5R"
			(at 177.8 46.99 0)
			(effects
				(font
					(size 1.27 1.27)
				)
				(justify left bottom)
				(hide yes)
			)
		)
		(pin "1"
		)
		(pin "2"
		)
		(instances
			(project "k410t-devboard"
				(path ""
					(reference "C33")
					(unit 1)
				)
			)
		)
	)
	(symbol
		(lib_id "antmicroCapacitors0603:C_47u_0603")
		(at 292.1 62.23 90)
		(mirror x)
		(unit 1)
		(exclude_from_sim no)
		(in_bom yes)
		(on_board yes)
		(dnp no)
		(property "Reference" "C105"
			(at 292.735 62.8777 90)
			(effects
				(font
					(size 1.27 1.27)
				)
				(justify right)
			)
		)
		(property "Value" "C_47u_0603"
			(at 302.26 82.55 0)
			(effects
				(font
					(size 1.27 1.27)
					(thickness 0.15)
				)
				(justify left bottom)
				(hide yes)
			)
		)
		(property "Footprint" "antmicro-footprints:C_0603_1608Metric"
			(at 304.8 82.55 0)
			(effects
				(font
					(size 1.27 1.27)
					(thickness 0.15)
				)
				(justify left bottom)
				(hide yes)
			)
		)
		(property "Datasheet" "https://www.murata.com/products/productdetail?partno=GRM188R60J476ME15%23"
			(at 307.34 82.55 0)
			(effects
				(font
					(size 1.27 1.27)
					(thickness 0.15)
				)
				(justify left bottom)
				(hide yes)
			)
		)
		(property "Description" ""
			(at 292.1 62.23 0)
			(effects
				(font
					(size 1.27 1.27)
				)
			)
		)
		(property "Manufacturer" "Murata"
			(at 312.42 82.55 0)
			(effects
				(font
					(size 1.27 1.27)
					(thickness 0.15)
				)
				(justify left bottom)
				(hide yes)
			)
		)
		(property "MPN" "GRM188R60J476ME15D"
			(at 309.88 82.55 0)
			(effects
				(font
					(size 1.27 1.27)
					(thickness 0.15)
				)
				(justify left bottom)
				(hide yes)
			)
		)
		(property "Val" "47u"
			(at 292.735 66.6877 90)
			(effects
				(font
					(size 1.27 1.27)
					(thickness 0.15)
				)
				(justify right)
			)
		)
		(property "License" "Apache-2.0"
			(at 314.96 82.55 0)
			(effects
				(font
					(size 1.27 1.27)
					(thickness 0.15)
				)
				(justify left bottom)
				(hide yes)
			)
		)
		(property "Author" "Antmicro"
			(at 317.5 82.55 0)
			(effects
				(font
					(size 1.27 1.27)
					(thickness 0.15)
				)
				(justify left bottom)
				(hide yes)
			)
		)
		(property "Voltage" ""
			(at 320.04 82.55 0)
			(effects
				(font
					(size 1.27 1.27)
				)
				(justify left bottom)
				(hide yes)
			)
		)
		(property "Dielectric" ""
			(at 322.58 82.55 0)
			(effects
				(font
					(size 1.27 1.27)
				)
				(justify left bottom)
				(hide yes)
			)
		)
		(pin "1"
		)
		(pin "2"
		)
		(instances
			(project "k410t-devboard"
				(path ""
					(reference "C105")
					(unit 1)
				)
			)
		)
	)
	(symbol
		(lib_id "antmicroCapacitors0402:C_100n_0402")
		(at 254 67.31 90)
		(unit 1)
		(exclude_from_sim no)
		(in_bom yes)
		(on_board yes)
		(dnp no)
		(property "Reference" "C75"
			(at 254.635 62.865 90)
			(effects
				(font
					(size 1.27 1.27)
				)
				(justify right)
			)
		)
		(property "Value" "C_100n_0402"
			(at 264.16 46.99 0)
			(effects
				(font
					(size 1.27 1.27)
					(thickness 0.15)
				)
				(justify left bottom)
				(hide yes)
			)
		)
		(property "Footprint" "antmicro-footprints:C_0402_1005Metric"
			(at 266.7 46.99 0)
			(effects
				(font
					(size 1.27 1.27)
					(thickness 0.15)
				)
				(justify left bottom)
				(hide yes)
			)
		)
		(property "Datasheet" "https://www.murata.com/products/productdetail?partno=GRM155R61H104KE14%23"
			(at 269.24 46.99 0)
			(effects
				(font
					(size 1.27 1.27)
					(thickness 0.15)
				)
				(justify left bottom)
				(hide yes)
			)
		)
		(property "Description" ""
			(at 254 67.31 0)
			(effects
				(font
					(size 1.27 1.27)
				)
			)
		)
		(property "Manufacturer" "Murata"
			(at 274.32 46.99 0)
			(effects
				(font
					(size 1.27 1.27)
					(thickness 0.15)
				)
				(justify left bottom)
				(hide yes)
			)
		)
		(property "MPN" "GRM155R61H104KE14D"
			(at 271.78 46.99 0)
			(effects
				(font
					(size 1.27 1.27)
					(thickness 0.15)
				)
				(justify left bottom)
				(hide yes)
			)
		)
		(property "Val" "100n"
			(at 254.635 66.675 90)
			(effects
				(font
					(size 1.27 1.27)
					(thickness 0.15)
				)
				(justify right)
			)
		)
		(property "License" "Apache-2.0"
			(at 276.86 46.99 0)
			(effects
				(font
					(size 1.27 1.27)
					(thickness 0.15)
				)
				(justify left bottom)
				(hide yes)
			)
		)
		(property "Author" "Antmicro"
			(at 279.4 46.99 0)
			(effects
				(font
					(size 1.27 1.27)
					(thickness 0.15)
				)
				(justify left bottom)
				(hide yes)
			)
		)
		(property "Voltage" "50V"
			(at 281.94 46.99 0)
			(effects
				(font
					(size 1.27 1.27)
				)
				(justify left bottom)
				(hide yes)
			)
		)
		(property "Dielectric" "X5R"
			(at 284.48 46.99 0)
			(effects
				(font
					(size 1.27 1.27)
				)
				(justify left bottom)
				(hide yes)
			)
		)
		(pin "1"
		)
		(pin "2"
		)
		(instances
			(project "k410t-devboard"
				(path ""
					(reference "C75")
					(unit 1)
				)
			)
		)
	)
	(symbol
		(lib_id "antmicroCapacitors0402:C_100n_0402")
		(at 276.86 67.31 90)
		(unit 1)
		(exclude_from_sim no)
		(in_bom yes)
		(on_board yes)
		(dnp no)
		(property "Reference" "C92"
			(at 277.495 62.865 90)
			(effects
				(font
					(size 1.27 1.27)
				)
				(justify right)
			)
		)
		(property "Value" "C_100n_0402"
			(at 287.02 46.99 0)
			(effects
				(font
					(size 1.27 1.27)
					(thickness 0.15)
				)
				(justify left bottom)
				(hide yes)
			)
		)
		(property "Footprint" "antmicro-footprints:C_0402_1005Metric"
			(at 289.56 46.99 0)
			(effects
				(font
					(size 1.27 1.27)
					(thickness 0.15)
				)
				(justify left bottom)
				(hide yes)
			)
		)
		(property "Datasheet" "https://www.murata.com/products/productdetail?partno=GRM155R61H104KE14%23"
			(at 292.1 46.99 0)
			(effects
				(font
					(size 1.27 1.27)
					(thickness 0.15)
				)
				(justify left bottom)
				(hide yes)
			)
		)
		(property "Description" ""
			(at 276.86 67.31 0)
			(effects
				(font
					(size 1.27 1.27)
				)
			)
		)
		(property "Manufacturer" "Murata"
			(at 297.18 46.99 0)
			(effects
				(font
					(size 1.27 1.27)
					(thickness 0.15)
				)
				(justify left bottom)
				(hide yes)
			)
		)
		(property "MPN" "GRM155R61H104KE14D"
			(at 294.64 46.99 0)
			(effects
				(font
					(size 1.27 1.27)
					(thickness 0.15)
				)
				(justify left bottom)
				(hide yes)
			)
		)
		(property "Val" "100n"
			(at 277.495 66.675 90)
			(effects
				(font
					(size 1.27 1.27)
					(thickness 0.15)
				)
				(justify right)
			)
		)
		(property "License" "Apache-2.0"
			(at 299.72 46.99 0)
			(effects
				(font
					(size 1.27 1.27)
					(thickness 0.15)
				)
				(justify left bottom)
				(hide yes)
			)
		)
		(property "Author" "Antmicro"
			(at 302.26 46.99 0)
			(effects
				(font
					(size 1.27 1.27)
					(thickness 0.15)
				)
				(justify left bottom)
				(hide yes)
			)
		)
		(property "Voltage" "50V"
			(at 304.8 46.99 0)
			(effects
				(font
					(size 1.27 1.27)
				)
				(justify left bottom)
				(hide yes)
			)
		)
		(property "Dielectric" "X5R"
			(at 307.34 46.99 0)
			(effects
				(font
					(size 1.27 1.27)
				)
				(justify left bottom)
				(hide yes)
			)
		)
		(pin "1"
		)
		(pin "2"
		)
		(instances
			(project "k410t-devboard"
				(path ""
					(reference "C92")
					(unit 1)
				)
			)
		)
	)
	(symbol
		(lib_id "antmicroCapacitors0603:C_47u_0603")
		(at 116.84 67.31 90)
		(unit 1)
		(exclude_from_sim no)
		(in_bom yes)
		(on_board yes)
		(dnp no)
		(property "Reference" "C7"
			(at 117.475 62.865 90)
			(effects
				(font
					(size 1.27 1.27)
				)
				(justify right)
			)
		)
		(property "Value" "C_47u_0603"
			(at 127 46.99 0)
			(effects
				(font
					(size 1.27 1.27)
					(thickness 0.15)
				)
				(justify left bottom)
				(hide yes)
			)
		)
		(property "Footprint" "antmicro-footprints:C_0603_1608Metric"
			(at 129.54 46.99 0)
			(effects
				(font
					(size 1.27 1.27)
					(thickness 0.15)
				)
				(justify left bottom)
				(hide yes)
			)
		)
		(property "Datasheet" "https://www.murata.com/products/productdetail?partno=GRM188R60J476ME15%23"
			(at 132.08 46.99 0)
			(effects
				(font
					(size 1.27 1.27)
					(thickness 0.15)
				)
				(justify left bottom)
				(hide yes)
			)
		)
		(property "Description" ""
			(at 116.84 67.31 0)
			(effects
				(font
					(size 1.27 1.27)
				)
			)
		)
		(property "Manufacturer" "Murata"
			(at 137.16 46.99 0)
			(effects
				(font
					(size 1.27 1.27)
					(thickness 0.15)
				)
				(justify left bottom)
				(hide yes)
			)
		)
		(property "MPN" "GRM188R60J476ME15D"
			(at 134.62 46.99 0)
			(effects
				(font
					(size 1.27 1.27)
					(thickness 0.15)
				)
				(justify left bottom)
				(hide yes)
			)
		)
		(property "Val" "47u"
			(at 117.475 66.675 90)
			(effects
				(font
					(size 1.27 1.27)
					(thickness 0.15)
				)
				(justify right)
			)
		)
		(property "License" "Apache-2.0"
			(at 139.7 46.99 0)
			(effects
				(font
					(size 1.27 1.27)
					(thickness 0.15)
				)
				(justify left bottom)
				(hide yes)
			)
		)
		(property "Author" "Antmicro"
			(at 142.24 46.99 0)
			(effects
				(font
					(size 1.27 1.27)
					(thickness 0.15)
				)
				(justify left bottom)
				(hide yes)
			)
		)
		(property "Voltage" ""
			(at 144.78 46.99 0)
			(effects
				(font
					(size 1.27 1.27)
				)
				(justify left bottom)
				(hide yes)
			)
		)
		(property "Dielectric" ""
			(at 147.32 46.99 0)
			(effects
				(font
					(size 1.27 1.27)
				)
				(justify left bottom)
				(hide yes)
			)
		)
		(pin "1"
		)
		(pin "2"
		)
		(instances
			(project "k410t-devboard"
				(path ""
					(reference "C7")
					(unit 1)
				)
			)
		)
	)
	(symbol
		(lib_id "antmicroCapacitors0402:C_100n_0402")
		(at 162.56 67.31 90)
		(unit 1)
		(exclude_from_sim no)
		(in_bom yes)
		(on_board yes)
		(dnp no)
		(property "Reference" "C44"
			(at 163.195 62.865 90)
			(effects
				(font
					(size 1.27 1.27)
				)
				(justify right)
			)
		)
		(property "Value" "C_100n_0402"
			(at 172.72 46.99 0)
			(effects
				(font
					(size 1.27 1.27)
					(thickness 0.15)
				)
				(justify left bottom)
				(hide yes)
			)
		)
		(property "Footprint" "antmicro-footprints:C_0402_1005Metric"
			(at 175.26 46.99 0)
			(effects
				(font
					(size 1.27 1.27)
					(thickness 0.15)
				)
				(justify left bottom)
				(hide yes)
			)
		)
		(property "Datasheet" "https://www.murata.com/products/productdetail?partno=GRM155R61H104KE14%23"
			(at 177.8 46.99 0)
			(effects
				(font
					(size 1.27 1.27)
					(thickness 0.15)
				)
				(justify left bottom)
				(hide yes)
			)
		)
		(property "Description" ""
			(at 162.56 67.31 0)
			(effects
				(font
					(size 1.27 1.27)
				)
			)
		)
		(property "Manufacturer" "Murata"
			(at 182.88 46.99 0)
			(effects
				(font
					(size 1.27 1.27)
					(thickness 0.15)
				)
				(justify left bottom)
				(hide yes)
			)
		)
		(property "MPN" "GRM155R61H104KE14D"
			(at 180.34 46.99 0)
			(effects
				(font
					(size 1.27 1.27)
					(thickness 0.15)
				)
				(justify left bottom)
				(hide yes)
			)
		)
		(property "Val" "100n"
			(at 163.195 66.675 90)
			(effects
				(font
					(size 1.27 1.27)
					(thickness 0.15)
				)
				(justify right)
			)
		)
		(property "License" "Apache-2.0"
			(at 185.42 46.99 0)
			(effects
				(font
					(size 1.27 1.27)
					(thickness 0.15)
				)
				(justify left bottom)
				(hide yes)
			)
		)
		(property "Author" "Antmicro"
			(at 187.96 46.99 0)
			(effects
				(font
					(size 1.27 1.27)
					(thickness 0.15)
				)
				(justify left bottom)
				(hide yes)
			)
		)
		(property "Voltage" "50V"
			(at 190.5 46.99 0)
			(effects
				(font
					(size 1.27 1.27)
				)
				(justify left bottom)
				(hide yes)
			)
		)
		(property "Dielectric" "X5R"
			(at 193.04 46.99 0)
			(effects
				(font
					(size 1.27 1.27)
				)
				(justify left bottom)
				(hide yes)
			)
		)
		(pin "1"
		)
		(pin "2"
		)
		(instances
			(project "k410t-devboard"
				(path ""
					(reference "C44")
					(unit 1)
				)
			)
		)
	)
	(symbol
		(lib_id "antmicroCapacitors0402:C_100n_0402")
		(at 139.7 67.31 90)
		(unit 1)
		(exclude_from_sim no)
		(in_bom yes)
		(on_board yes)
		(dnp no)
		(property "Reference" "C27"
			(at 140.335 62.865 90)
			(effects
				(font
					(size 1.27 1.27)
				)
				(justify right)
			)
		)
		(property "Value" "C_100n_0402"
			(at 149.86 46.99 0)
			(effects
				(font
					(size 1.27 1.27)
					(thickness 0.15)
				)
				(justify left bottom)
				(hide yes)
			)
		)
		(property "Footprint" "antmicro-footprints:C_0402_1005Metric"
			(at 152.4 46.99 0)
			(effects
				(font
					(size 1.27 1.27)
					(thickness 0.15)
				)
				(justify left bottom)
				(hide yes)
			)
		)
		(property "Datasheet" "https://www.murata.com/products/productdetail?partno=GRM155R61H104KE14%23"
			(at 154.94 46.99 0)
			(effects
				(font
					(size 1.27 1.27)
					(thickness 0.15)
				)
				(justify left bottom)
				(hide yes)
			)
		)
		(property "Description" ""
			(at 139.7 67.31 0)
			(effects
				(font
					(size 1.27 1.27)
				)
			)
		)
		(property "Manufacturer" "Murata"
			(at 160.02 46.99 0)
			(effects
				(font
					(size 1.27 1.27)
					(thickness 0.15)
				)
				(justify left bottom)
				(hide yes)
			)
		)
		(property "MPN" "GRM155R61H104KE14D"
			(at 157.48 46.99 0)
			(effects
				(font
					(size 1.27 1.27)
					(thickness 0.15)
				)
				(justify left bottom)
				(hide yes)
			)
		)
		(property "Val" "100n"
			(at 140.335 66.675 90)
			(effects
				(font
					(size 1.27 1.27)
					(thickness 0.15)
				)
				(justify right)
			)
		)
		(property "License" "Apache-2.0"
			(at 162.56 46.99 0)
			(effects
				(font
					(size 1.27 1.27)
					(thickness 0.15)
				)
				(justify left bottom)
				(hide yes)
			)
		)
		(property "Author" "Antmicro"
			(at 165.1 46.99 0)
			(effects
				(font
					(size 1.27 1.27)
					(thickness 0.15)
				)
				(justify left bottom)
				(hide yes)
			)
		)
		(property "Voltage" "50V"
			(at 167.64 46.99 0)
			(effects
				(font
					(size 1.27 1.27)
				)
				(justify left bottom)
				(hide yes)
			)
		)
		(property "Dielectric" "X5R"
			(at 170.18 46.99 0)
			(effects
				(font
					(size 1.27 1.27)
				)
				(justify left bottom)
				(hide yes)
			)
		)
		(pin "1"
		)
		(pin "2"
		)
		(instances
			(project "k410t-devboard"
				(path ""
					(reference "C27")
					(unit 1)
				)
			)
		)
	)
	(symbol
		(lib_id "antmicroCapacitors0402:C_100n_0402")
		(at 269.24 67.31 90)
		(unit 1)
		(exclude_from_sim no)
		(in_bom yes)
		(on_board yes)
		(dnp no)
		(property "Reference" "C87"
			(at 269.875 62.865 90)
			(effects
				(font
					(size 1.27 1.27)
				)
				(justify right)
			)
		)
		(property "Value" "C_100n_0402"
			(at 279.4 46.99 0)
			(effects
				(font
					(size 1.27 1.27)
					(thickness 0.15)
				)
				(justify left bottom)
				(hide yes)
			)
		)
		(property "Footprint" "antmicro-footprints:C_0402_1005Metric"
			(at 281.94 46.99 0)
			(effects
				(font
					(size 1.27 1.27)
					(thickness 0.15)
				)
				(justify left bottom)
				(hide yes)
			)
		)
		(property "Datasheet" "https://www.murata.com/products/productdetail?partno=GRM155R61H104KE14%23"
			(at 284.48 46.99 0)
			(effects
				(font
					(size 1.27 1.27)
					(thickness 0.15)
				)
				(justify left bottom)
				(hide yes)
			)
		)
		(property "Description" ""
			(at 269.24 67.31 0)
			(effects
				(font
					(size 1.27 1.27)
				)
			)
		)
		(property "Manufacturer" "Murata"
			(at 289.56 46.99 0)
			(effects
				(font
					(size 1.27 1.27)
					(thickness 0.15)
				)
				(justify left bottom)
				(hide yes)
			)
		)
		(property "MPN" "GRM155R61H104KE14D"
			(at 287.02 46.99 0)
			(effects
				(font
					(size 1.27 1.27)
					(thickness 0.15)
				)
				(justify left bottom)
				(hide yes)
			)
		)
		(property "Val" "100n"
			(at 269.875 66.675 90)
			(effects
				(font
					(size 1.27 1.27)
					(thickness 0.15)
				)
				(justify right)
			)
		)
		(property "License" "Apache-2.0"
			(at 292.1 46.99 0)
			(effects
				(font
					(size 1.27 1.27)
					(thickness 0.15)
				)
				(justify left bottom)
				(hide yes)
			)
		)
		(property "Author" "Antmicro"
			(at 294.64 46.99 0)
			(effects
				(font
					(size 1.27 1.27)
					(thickness 0.15)
				)
				(justify left bottom)
				(hide yes)
			)
		)
		(property "Voltage" "50V"
			(at 297.18 46.99 0)
			(effects
				(font
					(size 1.27 1.27)
				)
				(justify left bottom)
				(hide yes)
			)
		)
		(property "Dielectric" "X5R"
			(at 299.72 46.99 0)
			(effects
				(font
					(size 1.27 1.27)
				)
				(justify left bottom)
				(hide yes)
			)
		)
		(pin "1"
		)
		(pin "2"
		)
		(instances
			(project "k410t-devboard"
				(path ""
					(reference "C87")
					(unit 1)
				)
			)
		)
	)
	(symbol
		(lib_id "antmicroCapacitors0402:C_100n_0402")
		(at 124.46 67.31 90)
		(unit 1)
		(exclude_from_sim no)
		(in_bom yes)
		(on_board yes)
		(dnp no)
		(property "Reference" "C15"
			(at 125.095 62.865 90)
			(effects
				(font
					(size 1.27 1.27)
				)
				(justify right)
			)
		)
		(property "Value" "C_100n_0402"
			(at 134.62 46.99 0)
			(effects
				(font
					(size 1.27 1.27)
					(thickness 0.15)
				)
				(justify left bottom)
				(hide yes)
			)
		)
		(property "Footprint" "antmicro-footprints:C_0402_1005Metric"
			(at 137.16 46.99 0)
			(effects
				(font
					(size 1.27 1.27)
					(thickness 0.15)
				)
				(justify left bottom)
				(hide yes)
			)
		)
		(property "Datasheet" "https://www.murata.com/products/productdetail?partno=GRM155R61H104KE14%23"
			(at 139.7 46.99 0)
			(effects
				(font
					(size 1.27 1.27)
					(thickness 0.15)
				)
				(justify left bottom)
				(hide yes)
			)
		)
		(property "Description" ""
			(at 124.46 67.31 0)
			(effects
				(font
					(size 1.27 1.27)
				)
			)
		)
		(property "Manufacturer" "Murata"
			(at 144.78 46.99 0)
			(effects
				(font
					(size 1.27 1.27)
					(thickness 0.15)
				)
				(justify left bottom)
				(hide yes)
			)
		)
		(property "MPN" "GRM155R61H104KE14D"
			(at 142.24 46.99 0)
			(effects
				(font
					(size 1.27 1.27)
					(thickness 0.15)
				)
				(justify left bottom)
				(hide yes)
			)
		)
		(property "Val" "100n"
			(at 125.095 66.675 90)
			(effects
				(font
					(size 1.27 1.27)
					(thickness 0.15)
				)
				(justify right)
			)
		)
		(property "License" "Apache-2.0"
			(at 147.32 46.99 0)
			(effects
				(font
					(size 1.27 1.27)
					(thickness 0.15)
				)
				(justify left bottom)
				(hide yes)
			)
		)
		(property "Author" "Antmicro"
			(at 149.86 46.99 0)
			(effects
				(font
					(size 1.27 1.27)
					(thickness 0.15)
				)
				(justify left bottom)
				(hide yes)
			)
		)
		(property "Voltage" "50V"
			(at 152.4 46.99 0)
			(effects
				(font
					(size 1.27 1.27)
				)
				(justify left bottom)
				(hide yes)
			)
		)
		(property "Dielectric" "X5R"
			(at 154.94 46.99 0)
			(effects
				(font
					(size 1.27 1.27)
				)
				(justify left bottom)
				(hide yes)
			)
		)
		(pin "1"
		)
		(pin "2"
		)
		(instances
			(project "k410t-devboard"
				(path ""
					(reference "C15")
					(unit 1)
				)
			)
		)
	)
	(symbol
		(lib_id "antmicroCapacitors0402:C_100n_0402")
		(at 246.38 67.31 90)
		(unit 1)
		(exclude_from_sim no)
		(in_bom yes)
		(on_board yes)
		(dnp no)
		(property "Reference" "C67"
			(at 247.015 62.865 90)
			(effects
				(font
					(size 1.27 1.27)
				)
				(justify right)
			)
		)
		(property "Value" "C_100n_0402"
			(at 256.54 46.99 0)
			(effects
				(font
					(size 1.27 1.27)
					(thickness 0.15)
				)
				(justify left bottom)
				(hide yes)
			)
		)
		(property "Footprint" "antmicro-footprints:C_0402_1005Metric"
			(at 259.08 46.99 0)
			(effects
				(font
					(size 1.27 1.27)
					(thickness 0.15)
				)
				(justify left bottom)
				(hide yes)
			)
		)
		(property "Datasheet" "https://www.murata.com/products/productdetail?partno=GRM155R61H104KE14%23"
			(at 261.62 46.99 0)
			(effects
				(font
					(size 1.27 1.27)
					(thickness 0.15)
				)
				(justify left bottom)
				(hide yes)
			)
		)
		(property "Description" ""
			(at 246.38 67.31 0)
			(effects
				(font
					(size 1.27 1.27)
				)
			)
		)
		(property "Manufacturer" "Murata"
			(at 266.7 46.99 0)
			(effects
				(font
					(size 1.27 1.27)
					(thickness 0.15)
				)
				(justify left bottom)
				(hide yes)
			)
		)
		(property "MPN" "GRM155R61H104KE14D"
			(at 264.16 46.99 0)
			(effects
				(font
					(size 1.27 1.27)
					(thickness 0.15)
				)
				(justify left bottom)
				(hide yes)
			)
		)
		(property "Val" "100n"
			(at 247.015 66.675 90)
			(effects
				(font
					(size 1.27 1.27)
					(thickness 0.15)
				)
				(justify right)
			)
		)
		(property "License" "Apache-2.0"
			(at 269.24 46.99 0)
			(effects
				(font
					(size 1.27 1.27)
					(thickness 0.15)
				)
				(justify left bottom)
				(hide yes)
			)
		)
		(property "Author" "Antmicro"
			(at 271.78 46.99 0)
			(effects
				(font
					(size 1.27 1.27)
					(thickness 0.15)
				)
				(justify left bottom)
				(hide yes)
			)
		)
		(property "Voltage" "50V"
			(at 274.32 46.99 0)
			(effects
				(font
					(size 1.27 1.27)
				)
				(justify left bottom)
				(hide yes)
			)
		)
		(property "Dielectric" "X5R"
			(at 276.86 46.99 0)
			(effects
				(font
					(size 1.27 1.27)
				)
				(justify left bottom)
				(hide yes)
			)
		)
		(pin "1"
		)
		(pin "2"
		)
		(instances
			(project "k410t-devboard"
				(path ""
					(reference "C67")
					(unit 1)
				)
			)
		)
	)
	(symbol
		(lib_id "antmicroCapacitors0402:C_100n_0402")
		(at 284.48 67.31 90)
		(unit 1)
		(exclude_from_sim no)
		(in_bom yes)
		(on_board yes)
		(dnp no)
		(property "Reference" "C98"
			(at 285.115 62.865 90)
			(effects
				(font
					(size 1.27 1.27)
				)
				(justify right)
			)
		)
		(property "Value" "C_100n_0402"
			(at 294.64 46.99 0)
			(effects
				(font
					(size 1.27 1.27)
					(thickness 0.15)
				)
				(justify left bottom)
				(hide yes)
			)
		)
		(property "Footprint" "antmicro-footprints:C_0402_1005Metric"
			(at 297.18 46.99 0)
			(effects
				(font
					(size 1.27 1.27)
					(thickness 0.15)
				)
				(justify left bottom)
				(hide yes)
			)
		)
		(property "Datasheet" "https://www.murata.com/products/productdetail?partno=GRM155R61H104KE14%23"
			(at 299.72 46.99 0)
			(effects
				(font
					(size 1.27 1.27)
					(thickness 0.15)
				)
				(justify left bottom)
				(hide yes)
			)
		)
		(property "Description" ""
			(at 284.48 67.31 0)
			(effects
				(font
					(size 1.27 1.27)
				)
			)
		)
		(property "Manufacturer" "Murata"
			(at 304.8 46.99 0)
			(effects
				(font
					(size 1.27 1.27)
					(thickness 0.15)
				)
				(justify left bottom)
				(hide yes)
			)
		)
		(property "MPN" "GRM155R61H104KE14D"
			(at 302.26 46.99 0)
			(effects
				(font
					(size 1.27 1.27)
					(thickness 0.15)
				)
				(justify left bottom)
				(hide yes)
			)
		)
		(property "Val" "100n"
			(at 285.115 66.675 90)
			(effects
				(font
					(size 1.27 1.27)
					(thickness 0.15)
				)
				(justify right)
			)
		)
		(property "License" "Apache-2.0"
			(at 307.34 46.99 0)
			(effects
				(font
					(size 1.27 1.27)
					(thickness 0.15)
				)
				(justify left bottom)
				(hide yes)
			)
		)
		(property "Author" "Antmicro"
			(at 309.88 46.99 0)
			(effects
				(font
					(size 1.27 1.27)
					(thickness 0.15)
				)
				(justify left bottom)
				(hide yes)
			)
		)
		(property "Voltage" "50V"
			(at 312.42 46.99 0)
			(effects
				(font
					(size 1.27 1.27)
				)
				(justify left bottom)
				(hide yes)
			)
		)
		(property "Dielectric" "X5R"
			(at 314.96 46.99 0)
			(effects
				(font
					(size 1.27 1.27)
				)
				(justify left bottom)
				(hide yes)
			)
		)
		(pin "1"
		)
		(pin "2"
		)
		(instances
			(project "k410t-devboard"
				(path ""
					(reference "C98")
					(unit 1)
				)
			)
		)
	)
	(symbol
		(lib_id "antmicropower:+3.3V")
		(at 298.45 57.15 0)
		(unit 1)
		(exclude_from_sim no)
		(in_bom yes)
		(on_board yes)
		(dnp no)
		(fields_autoplaced yes)
		(property "Reference" "#PWR023"
			(at 298.45 60.96 0)
			(effects
				(font
					(size 1.27 1.27)
				)
				(hide yes)
			)
		)
		(property "Value" "+3V3"
			(at 298.45 53.594 0)
			(effects
				(font
					(size 1.27 1.27)
				)
			)
		)
		(property "Footprint" ""
			(at 298.45 57.15 0)
			(effects
				(font
					(size 1.27 1.27)
				)
				(hide yes)
			)
		)
		(property "Datasheet" ""
			(at 298.45 57.15 0)
			(effects
				(font
					(size 1.27 1.27)
				)
				(hide yes)
			)
		)
		(property "Description" ""
			(at 298.45 57.15 0)
			(effects
				(font
					(size 1.27 1.27)
				)
			)
		)
		(pin "1"
		)
		(instances
			(project "k410t-devboard"
				(path ""
					(reference "#PWR023")
					(unit 1)
				)
			)
		)
	)
	(symbol
		(lib_id "antmicroCapacitors0402:C_100n_0402")
		(at 170.18 67.31 90)
		(unit 1)
		(exclude_from_sim no)
		(in_bom yes)
		(on_board yes)
		(dnp no)
		(property "Reference" "C47"
			(at 170.815 62.865 90)
			(effects
				(font
					(size 1.27 1.27)
				)
				(justify right)
			)
		)
		(property "Value" "C_100n_0402"
			(at 180.34 46.99 0)
			(effects
				(font
					(size 1.27 1.27)
					(thickness 0.15)
				)
				(justify left bottom)
				(hide yes)
			)
		)
		(property "Footprint" "antmicro-footprints:C_0402_1005Metric"
			(at 182.88 46.99 0)
			(effects
				(font
					(size 1.27 1.27)
					(thickness 0.15)
				)
				(justify left bottom)
				(hide yes)
			)
		)
		(property "Datasheet" "https://www.murata.com/products/productdetail?partno=GRM155R61H104KE14%23"
			(at 185.42 46.99 0)
			(effects
				(font
					(size 1.27 1.27)
					(thickness 0.15)
				)
				(justify left bottom)
				(hide yes)
			)
		)
		(property "Description" ""
			(at 170.18 67.31 0)
			(effects
				(font
					(size 1.27 1.27)
				)
			)
		)
		(property "Manufacturer" "Murata"
			(at 190.5 46.99 0)
			(effects
				(font
					(size 1.27 1.27)
					(thickness 0.15)
				)
				(justify left bottom)
				(hide yes)
			)
		)
		(property "MPN" "GRM155R61H104KE14D"
			(at 187.96 46.99 0)
			(effects
				(font
					(size 1.27 1.27)
					(thickness 0.15)
				)
				(justify left bottom)
				(hide yes)
			)
		)
		(property "Val" "100n"
			(at 170.815 66.675 90)
			(effects
				(font
					(size 1.27 1.27)
					(thickness 0.15)
				)
				(justify right)
			)
		)
		(property "License" "Apache-2.0"
			(at 193.04 46.99 0)
			(effects
				(font
					(size 1.27 1.27)
					(thickness 0.15)
				)
				(justify left bottom)
				(hide yes)
			)
		)
		(property "Author" "Antmicro"
			(at 195.58 46.99 0)
			(effects
				(font
					(size 1.27 1.27)
					(thickness 0.15)
				)
				(justify left bottom)
				(hide yes)
			)
		)
		(property "Voltage" "50V"
			(at 198.12 46.99 0)
			(effects
				(font
					(size 1.27 1.27)
				)
				(justify left bottom)
				(hide yes)
			)
		)
		(property "Dielectric" "X5R"
			(at 200.66 46.99 0)
			(effects
				(font
					(size 1.27 1.27)
				)
				(justify left bottom)
				(hide yes)
			)
		)
		(pin "1"
		)
		(pin "2"
		)
		(instances
			(project "k410t-devboard"
				(path ""
					(reference "C47")
					(unit 1)
				)
			)
		)
	)
)
